G04 ================== begin FILE IDENTIFICATION RECORD ==================*
G04 Layout Name:  x887571-005_osp.brd*
G04 Film Name:    lyr3*
G04 File Format:  Gerber RS274X*
G04 File Origin:  Cadence Allegro 16.3-S036*
G04 Origin Date:  Thu Jul 03 00:06:57 2014*
G04 *
G04 Layer:  VIA CLASS/LYR3*
G04 Layer:  PIN/LYR3*
G04 Layer:  ETCH/LYR3*
G04 Layer:  DRAWING FORMAT/COMMON TEXT*
G04 Layer:  BOARD GEOMETRY/LAYER 3 TEXT*
G04 *
G04 Offset:    (0.0000 0.0000)*
G04 Mirror:    No*
G04 Mode:      Positive*
G04 Rotation:  0*
G04 FullContactRelief:  No*
G04 UndefLineWidth:     4.0000*
G04 ================== end FILE IDENTIFICATION RECORD ====================*
%FSLAX25Y25*MOIN*%
%IR0*IPPOS*OFA0.00000B0.00000*MIA0B0*SFA1.00000B1.00000*%
%ADD10C,.022*%
%ADD12C,.05*%
%ADD11C,.032*%
%ADD14C,.044*%
%ADD15C,.027*%
%ADD13C,.054*%
%ADD16C,.079*%
%ADD17C,.22*%
%ADD18C,.01*%
%ADD19C,.02*%
%ADD20C,.012*%
%ADD21C,.013*%
%ADD22C,.015*%
%ADD23C,.004*%
%ADD24C,.005*%
%ADD25C,.006*%
%ADD26C,.0051*%
%ADD27C,.007*%
%ADD28C,.008*%
%ADD30C,.032*%
%ADD36C,.046*%
%ADD34C,.064*%
%ADD31C,.073*%
%ADD35C,.074*%
%ADD32C,.098*%
%ADD33C,.099*%
%ADD29C,.154001*%
%ADD38C,.186001*%
%ADD37C,.186001*%
G75*
%LPD*%
G75*
G36*
G01X-1440241Y-14409D02*
Y9213D01*
G02X-1432598Y16855I7643J0D01*
G01X-1326855D01*
X-1325500Y15500D01*
Y-25710D01*
G03Y-28208I1000J-1249D01*
G01Y-80655D01*
X-1325627Y-80727D01*
G03X-1323824Y-83356I787J-1393D01*
G01X-1323648Y-83212D01*
X-1321000Y-85860D01*
Y-90500D01*
X-1322860Y-92360D01*
Y-95980D01*
X-1320340Y-98500D01*
X-1304300D01*
X-1289800Y-113000D01*
Y-179700D01*
X-1294050Y-183950D01*
X-1453994D01*
X-1454025Y-183875D01*
X-1455425D01*
X-1455500Y-183800D01*
Y-90000D01*
X-1448600Y-83100D01*
Y-83000D01*
X-1445700Y-80100D01*
Y-59300D01*
X-1454600Y-50400D01*
X-1607000D01*
X-1621320Y-36080D01*
Y-23013D01*
G02X-1620806Y-22514I500J0D01*
G03X-1617131Y-18937I98J3577D01*
G01Y16175D01*
X-1616226Y17080D01*
X-1461294D01*
X-1460389Y16175D01*
Y-14409D01*
G03X-1452283Y-22515I8106J0D01*
G01X-1448346D01*
G03X-1440241Y-14409I0J8106D01*
G37*
G36*
G01X-1021120Y15643D02*
G03X-1018880I1120J-1143D01*
G02X-1018530Y16500I350J357D01*
G01X-996470D01*
G02X-996120Y15643I0J-500D01*
G03X-993880I1120J-1143D01*
G02X-993530Y16500I350J357D01*
G01X-971470D01*
G02X-971120Y15643I0J-500D01*
G03X-968880I1120J-1143D01*
G02X-968530Y16500I350J357D01*
G01X-946470D01*
G02X-946120Y15643I0J-500D01*
G03X-943880I1120J-1143D01*
G02X-943530Y16500I350J357D01*
G01X-923470D01*
G02X-923120Y15643I0J-500D01*
G03X-920880I1120J-1143D01*
G02X-920530Y16500I350J357D01*
G01X-898970D01*
G02X-898620Y15643I0J-500D01*
G03X-896380I1120J-1143D01*
G02X-896030Y16500I350J357D01*
G01X-873970D01*
G02X-873620Y15643I0J-500D01*
G03X-871380I1120J-1143D01*
G02X-871030Y16500I350J357D01*
G01X-849470D01*
G02X-849120Y15643I0J-500D01*
G03X-846880I1120J-1143D01*
G02X-846530Y16500I350J357D01*
G01X-823970D01*
G02X-823620Y15643I0J-500D01*
G03X-821380I1120J-1143D01*
G02X-821030Y16500I350J357D01*
G01X-798970D01*
G02X-798620Y15643I0J-500D01*
G03X-796380I1120J-1143D01*
G02X-796030Y16500I350J357D01*
G01X-773970D01*
G02X-773620Y15643I0J-500D01*
G03X-771380I1120J-1143D01*
G02X-771030Y16500I350J357D01*
G01X-748970D01*
G02X-748620Y15643I0J-500D01*
G03X-746380I1120J-1143D01*
G02X-746030Y16500I350J357D01*
G01X-723970D01*
G02X-723620Y15643I0J-500D01*
G03X-721380I1120J-1143D01*
G02X-721030Y16500I350J357D01*
G01X-698970D01*
G02X-698620Y15643I0J-500D01*
G03X-696380I1120J-1143D01*
G02X-696030Y16500I350J357D01*
G01X-673970D01*
G02X-673620Y15643I0J-500D01*
G03X-671380I1120J-1143D01*
G02X-671030Y16500I350J357D01*
G01X-646470D01*
G02X-646120Y15643I0J-500D01*
G03X-643880I1120J-1143D01*
G02X-643530Y16500I350J357D01*
G01X-459000D01*
Y-86500D01*
X-443000Y-102500D01*
X-427500D01*
X-422000Y-108000D01*
Y-181000D01*
X-473500D01*
X-474000Y-181500D01*
X-584500D01*
Y-71000D01*
X-601100Y-54400D01*
Y-54300D01*
X-715200D01*
X-718400Y-57500D01*
Y-57600D01*
X-754000Y-93200D01*
Y-183000D01*
X-1027000D01*
Y16450D01*
X-1026950Y16500D01*
X-1021470D01*
G02X-1021120Y15643I0J-500D01*
G37*
G36*
G01X-899782Y-186850D02*
X-885782D01*
Y-184850D01*
X-899782D01*
X-903782D01*
Y-186850D01*
X-899782D01*
G37*
%LPC*%
G75*
G36*
G01X-1347998Y-169894D02*
G02X-1360173Y-158465I-8891J2729D01*
G03X-1360221Y-157514I-177J468D01*
G02X-1353556I3333J12514D01*
G03X-1353604Y-158465I129J-483D01*
G02X-1347998Y-164437I-3285J-8701D01*
G02Y-169894I-8891J-2729D01*
G37*
G36*
G01X-1411378Y-134126D02*
Y-145669D01*
G02X-1434764I-11693J0D01*
G01Y-134126D01*
G02X-1411378I11693J12078D01*
G37*
G36*
G01X-1347998Y-116208D02*
G02X-1347689Y-120301I-8891J-2729D01*
G02X-1347998Y-116208I-9199J1364D01*
G37*
G36*
G01X-1315527Y-144838D02*
G02X-1317420Y-147362I3519J-4611D01*
G03X-1318127Y-146743I-467J180D01*
G02X-1316318Y-144333I-1756J3200D01*
G03X-1315527Y-144838I488J-108D01*
G37*
G36*
G01X-989774Y-176279D02*
G02X-991959I-1093J-2304D01*
G03Y-175375I-214J452D01*
G02X-989774I1093J2304D01*
G03Y-176279I214J-452D01*
G37*
G36*
G01X-997648Y-171160D02*
G02X-999833I-1093J-2304D01*
G03Y-170257I-214J452D01*
G02X-997648I1093J2304D01*
G03Y-171160I214J-452D01*
G37*
G36*
G01X-436518Y-147362D02*
G02X-438410Y-144838I-5412J-2087D01*
G03X-437619Y-144333I303J397D01*
G02X-435811Y-146743I3564J789D01*
G03X-436518Y-147362I-240J-438D01*
G37*
G36*
G01X-1004364Y-179783D02*
Y-181827D01*
X-1008864D01*
Y-179783D01*
G02Y-177383I2250J1200D01*
G01Y-174271D01*
G02Y-171871I2250J1200D01*
G01Y-169827D01*
X-1004364D01*
Y-171871D01*
G02Y-174271I-2250J-1200D01*
G01Y-177383D01*
G02Y-179783I-2250J-1200D01*
G37*
G36*
G01X-972868D02*
Y-181827D01*
X-977368D01*
Y-179783D01*
G02Y-177383I2250J1200D01*
G01Y-174271D01*
G02Y-171871I2250J1200D01*
G01Y-169827D01*
X-972868D01*
Y-171871D01*
G02Y-174271I-2250J-1200D01*
G01Y-177383D01*
G02Y-179783I-2250J-1200D01*
G37*
G36*
G01X-1012238Y-174665D02*
Y-176709D01*
X-1016738D01*
Y-174665D01*
G02Y-172265I2250J1200D01*
G01Y-169153D01*
G02Y-166753I2250J1200D01*
G01Y-164709D01*
X-1012238D01*
Y-166753D01*
G02Y-169153I-2250J-1200D01*
G01Y-172265D01*
G02Y-174665I-2250J-1200D01*
G37*
G36*
G01X-980742D02*
Y-176709D01*
X-985242D01*
Y-174665D01*
G02Y-172265I2250J1200D01*
G01Y-169153D01*
G02Y-166753I2250J1200D01*
G01Y-164709D01*
X-980742D01*
Y-166753D01*
G02Y-169153I-2250J-1200D01*
G01Y-172265D01*
G02Y-174665I-2250J-1200D01*
G37*
G36*
G01X-1004364Y-163247D02*
Y-165291D01*
X-1008864D01*
Y-163247D01*
G02Y-160847I2250J1200D01*
G01Y-157735D01*
G02Y-155335I2250J1200D01*
G01Y-153291D01*
X-1004364D01*
Y-155335D01*
G02Y-157735I-2250J-1200D01*
G01Y-160847D01*
G02Y-163247I-2250J-1200D01*
G37*
G36*
G01X-988616D02*
Y-165291D01*
X-993116D01*
Y-163247D01*
G02Y-160847I2250J1200D01*
G01Y-157735D01*
G02Y-155335I2250J1200D01*
G01Y-153291D01*
X-988616D01*
Y-155335D01*
G02Y-157735I-2250J-1200D01*
G01Y-160847D01*
G02Y-163247I-2250J-1200D01*
G37*
G36*
G01X-972868D02*
Y-165291D01*
X-977368D01*
Y-163247D01*
G02Y-160847I2250J1200D01*
G01Y-157735D01*
G02Y-155335I2250J1200D01*
G01Y-153291D01*
X-972868D01*
Y-155335D01*
G02Y-157735I-2250J-1200D01*
G01Y-160847D01*
G02Y-163247I-2250J-1200D01*
G37*
G36*
G01X-1012238Y-158129D02*
Y-160173D01*
X-1016738D01*
Y-158129D01*
G02Y-155729I2250J1200D01*
G01Y-152617D01*
G02Y-150217I2250J1200D01*
G01Y-148173D01*
X-1012238D01*
Y-150217D01*
G02Y-152617I-2250J-1200D01*
G01Y-155729D01*
G02Y-158129I-2250J-1200D01*
G37*
G36*
G01X-996490D02*
Y-160173D01*
X-1000990D01*
Y-158129D01*
G02Y-155729I2250J1200D01*
G01Y-152617D01*
G02Y-150217I2250J1200D01*
G01Y-148173D01*
X-996490D01*
Y-150217D01*
G02Y-152617I-2250J-1200D01*
G01Y-155729D01*
G02Y-158129I-2250J-1200D01*
G37*
G36*
G01X-980742D02*
Y-160173D01*
X-985242D01*
Y-158129D01*
G02Y-155729I2250J1200D01*
G01Y-152617D01*
G02Y-150217I2250J1200D01*
G01Y-148173D01*
X-980742D01*
Y-150217D01*
G02Y-152617I-2250J-1200D01*
G01Y-155729D01*
G02Y-158129I-2250J-1200D01*
G37*
G36*
G01X-1004364Y-146712D02*
Y-148756D01*
X-1008864D01*
Y-146712D01*
G02Y-144312I2250J1200D01*
G01Y-141200D01*
G02Y-138800I2250J1200D01*
G01Y-136756D01*
X-1004364D01*
Y-138800D01*
G02Y-141200I-2250J-1200D01*
G01Y-144312D01*
G02Y-146712I-2250J-1200D01*
G37*
G36*
G01X-988616D02*
Y-148756D01*
X-993116D01*
Y-146712D01*
G02Y-144312I2250J1200D01*
G01Y-141200D01*
G02Y-138800I2250J1200D01*
G01Y-136756D01*
X-988616D01*
Y-138800D01*
G02Y-141200I-2250J-1200D01*
G01Y-144312D01*
G02Y-146712I-2250J-1200D01*
G37*
G36*
G01X-972868D02*
Y-148756D01*
X-977368D01*
Y-146712D01*
G02Y-144312I2250J1200D01*
G01Y-141200D01*
G02Y-138800I2250J1200D01*
G01Y-136756D01*
X-972868D01*
Y-138800D01*
G02Y-141200I-2250J-1200D01*
G01Y-144312D01*
G02Y-146712I-2250J-1200D01*
G37*
G36*
G01X-1012238Y-141594D02*
Y-143638D01*
X-1016738D01*
Y-141594D01*
G02Y-139194I2250J1200D01*
G01Y-136082D01*
G02Y-133682I2250J1200D01*
G01Y-131638D01*
X-1012238D01*
Y-133682D01*
G02Y-136082I-2250J-1200D01*
G01Y-139194D01*
G02Y-141594I-2250J-1200D01*
G37*
G36*
G01X-996490D02*
Y-143638D01*
X-1000990D01*
Y-141594D01*
G02Y-139194I2250J1200D01*
G01Y-136082D01*
G02Y-133682I2250J1200D01*
G01Y-131638D01*
X-996490D01*
Y-133682D01*
G02Y-136082I-2250J-1200D01*
G01Y-139194D01*
G02Y-141594I-2250J-1200D01*
G37*
G36*
G01X-980742D02*
Y-143638D01*
X-985242D01*
Y-141594D01*
G02Y-139194I2250J1200D01*
G01Y-136082D01*
G02Y-133682I2250J1200D01*
G01Y-131638D01*
X-980742D01*
Y-133682D01*
G02Y-136082I-2250J-1200D01*
G01Y-139194D01*
G02Y-141594I-2250J-1200D01*
G37*
G36*
G01X-1009017Y-94669D02*
X-1012586Y-96333D01*
X-1013569Y-95924D01*
X-1014734Y-93427D01*
X-1013844Y-90840D01*
X-1012416Y-90174D01*
X-1009863Y-91155D01*
X-1008698Y-93653D01*
X-1009017Y-94669D01*
G37*
G36*
G01X-1012452Y-96928D02*
X-1008922Y-95185D01*
X-1007929Y-95571D01*
X-1006708Y-98042D01*
X-1007540Y-100648D01*
X-1008952Y-101346D01*
X-1011527Y-100423D01*
X-1012748Y-97952D01*
X-1012452Y-96928D01*
G37*
G36*
G01X-1009017Y-79708D02*
X-1012586Y-81372D01*
X-1013569Y-80964D01*
X-1014734Y-78466D01*
X-1013844Y-75879D01*
X-1012416Y-75214D01*
X-1009863Y-76194D01*
X-1008698Y-78692D01*
X-1009017Y-79708D01*
G37*
G36*
G01X-1012452Y-81968D02*
X-1008922Y-80224D01*
X-1007929Y-80610D01*
X-1006708Y-83081D01*
X-1007540Y-85687D01*
X-1008952Y-86385D01*
X-1011527Y-85462D01*
X-1012748Y-82991D01*
X-1012452Y-81968D01*
G37*
G36*
G01Y-67007D02*
X-1008922Y-65263D01*
X-1007929Y-65650D01*
X-1006708Y-68121D01*
X-1007540Y-70727D01*
X-1008952Y-71424D01*
X-1011527Y-70501D01*
X-1012748Y-68030D01*
X-1012452Y-67007D01*
G37*
G36*
G01Y-52047D02*
X-1008922Y-50303D01*
X-1007929Y-50689D01*
X-1006708Y-53160D01*
X-1007540Y-55766D01*
X-1008952Y-56464D01*
X-1011527Y-55541D01*
X-1012748Y-53070D01*
X-1012452Y-52047D01*
G37*
G36*
G01X-1009017Y-64748D02*
X-1012586Y-66412D01*
X-1013569Y-66003D01*
X-1014734Y-63505D01*
X-1013844Y-60919D01*
X-1012416Y-60253D01*
X-1009863Y-61234D01*
X-1008698Y-63732D01*
X-1009017Y-64748D01*
G37*
G36*
G01Y-49787D02*
X-1012586Y-51451D01*
X-1013569Y-51043D01*
X-1014734Y-48545D01*
X-1013844Y-45958D01*
X-1012416Y-45293D01*
X-1009863Y-46273D01*
X-1008698Y-48771D01*
X-1009017Y-49787D01*
G37*
G36*
G01X-1003593Y-96928D02*
X-1000064Y-95185D01*
X-999071Y-95571D01*
X-997850Y-98042D01*
X-998682Y-100648D01*
X-1000094Y-101346D01*
X-1002669Y-100423D01*
X-1003890Y-97952D01*
X-1003593Y-96928D01*
G37*
G36*
G01X-1000159Y-94669D02*
X-1003727Y-96333D01*
X-1004711Y-95924D01*
X-1005876Y-93427D01*
X-1004986Y-90840D01*
X-1003558Y-90174D01*
X-1001004Y-91155D01*
X-999840Y-93653D01*
X-1000159Y-94669D01*
G37*
G36*
G01X-1003593Y-67007D02*
X-1000064Y-65263D01*
X-999071Y-65650D01*
X-997850Y-68121D01*
X-998682Y-70727D01*
X-1000094Y-71424D01*
X-1002669Y-70501D01*
X-1003890Y-68030D01*
X-1003593Y-67007D01*
G37*
G36*
G01Y-81968D02*
X-1000064Y-80224D01*
X-999071Y-80610D01*
X-997850Y-83081D01*
X-998682Y-85687D01*
X-1000094Y-86385D01*
X-1002669Y-85462D01*
X-1003890Y-82991D01*
X-1003593Y-81968D01*
G37*
G36*
G01X-1000159Y-79708D02*
X-1003727Y-81372D01*
X-1004711Y-80964D01*
X-1005876Y-78466D01*
X-1004986Y-75879D01*
X-1003558Y-75214D01*
X-1001004Y-76194D01*
X-999840Y-78692D01*
X-1000159Y-79708D01*
G37*
G36*
G01X-1003593Y-52047D02*
X-1000064Y-50303D01*
X-999071Y-50689D01*
X-997850Y-53160D01*
X-998682Y-55766D01*
X-1000094Y-56464D01*
X-1002669Y-55541D01*
X-1003890Y-53070D01*
X-1003593Y-52047D01*
G37*
G36*
G01X-1000159Y-64748D02*
X-1003727Y-66412D01*
X-1004711Y-66003D01*
X-1005876Y-63505D01*
X-1004986Y-60919D01*
X-1003558Y-60253D01*
X-1001004Y-61234D01*
X-999840Y-63732D01*
X-1000159Y-64748D01*
G37*
G36*
G01X-969144Y-96928D02*
X-965615Y-95185D01*
X-964622Y-95571D01*
X-963401Y-98042D01*
X-964233Y-100648D01*
X-965645Y-101346D01*
X-968220Y-100423D01*
X-969441Y-97952D01*
X-969144Y-96928D01*
G37*
G36*
G01X-965710Y-94669D02*
X-969279Y-96333D01*
X-970262Y-95924D01*
X-971427Y-93427D01*
X-970537Y-90840D01*
X-969109Y-90174D01*
X-966556Y-91155D01*
X-965391Y-93653D01*
X-965710Y-94669D01*
G37*
G36*
G01X-969144Y-67007D02*
X-965615Y-65263D01*
X-964622Y-65650D01*
X-963401Y-68121D01*
X-964233Y-70727D01*
X-965645Y-71424D01*
X-968220Y-70501D01*
X-969441Y-68030D01*
X-969144Y-67007D01*
G37*
G36*
G01Y-81968D02*
X-965615Y-80224D01*
X-964622Y-80610D01*
X-963401Y-83081D01*
X-964233Y-85687D01*
X-965645Y-86385D01*
X-968220Y-85462D01*
X-969441Y-82991D01*
X-969144Y-81968D01*
G37*
G36*
G01X-965710Y-79708D02*
X-969279Y-81372D01*
X-970262Y-80964D01*
X-971427Y-78466D01*
X-970537Y-75879D01*
X-969109Y-75214D01*
X-966556Y-76194D01*
X-965391Y-78692D01*
X-965710Y-79708D01*
G37*
G36*
G01X-969144Y-52047D02*
X-965615Y-50303D01*
X-964622Y-50689D01*
X-963401Y-53160D01*
X-964233Y-55766D01*
X-965645Y-56464D01*
X-968220Y-55541D01*
X-969441Y-53070D01*
X-969144Y-52047D01*
G37*
G36*
G01X-965710Y-64748D02*
X-969279Y-66412D01*
X-970262Y-66003D01*
X-971427Y-63505D01*
X-970537Y-60919D01*
X-969109Y-60253D01*
X-966556Y-61234D01*
X-965391Y-63732D01*
X-965710Y-64748D01*
G37*
G36*
G01Y-49787D02*
X-969279Y-51451D01*
X-970262Y-51043D01*
X-971427Y-48545D01*
X-970537Y-45958D01*
X-969109Y-45293D01*
X-966556Y-46273D01*
X-965391Y-48771D01*
X-965710Y-49787D01*
G37*
G36*
G01X-956852Y-94669D02*
X-960420Y-96333D01*
X-961404Y-95924D01*
X-962569Y-93427D01*
X-961679Y-90840D01*
X-960251Y-90174D01*
X-957697Y-91155D01*
X-956533Y-93653D01*
X-956852Y-94669D01*
G37*
G36*
G01X-960286Y-96928D02*
X-956756Y-95185D01*
X-955764Y-95571D01*
X-954543Y-98042D01*
X-955375Y-100648D01*
X-956787Y-101346D01*
X-959362Y-100423D01*
X-960583Y-97952D01*
X-960286Y-96928D01*
G37*
G36*
G01X-956852Y-79708D02*
X-960420Y-81372D01*
X-961404Y-80964D01*
X-962569Y-78466D01*
X-961679Y-75879D01*
X-960251Y-75214D01*
X-957697Y-76194D01*
X-956533Y-78692D01*
X-956852Y-79708D01*
G37*
G36*
G01X-960286Y-81968D02*
X-956756Y-80224D01*
X-955764Y-80610D01*
X-954543Y-83081D01*
X-955375Y-85687D01*
X-956787Y-86385D01*
X-959362Y-85462D01*
X-960583Y-82991D01*
X-960286Y-81968D01*
G37*
G36*
G01Y-67007D02*
X-956756Y-65263D01*
X-955764Y-65650D01*
X-954543Y-68121D01*
X-955375Y-70727D01*
X-956787Y-71424D01*
X-959362Y-70501D01*
X-960583Y-68030D01*
X-960286Y-67007D01*
G37*
G36*
G01X-956852Y-64748D02*
X-960420Y-66412D01*
X-961404Y-66003D01*
X-962569Y-63505D01*
X-961679Y-60919D01*
X-960251Y-60253D01*
X-957697Y-61234D01*
X-956533Y-63732D01*
X-956852Y-64748D01*
G37*
G36*
G01X-960286Y-52047D02*
X-956756Y-50303D01*
X-955764Y-50689D01*
X-954543Y-53160D01*
X-955375Y-55766D01*
X-956787Y-56464D01*
X-959362Y-55541D01*
X-960583Y-53070D01*
X-960286Y-52047D01*
G37*
G36*
G01X-549173Y-104441D02*
Y-115984D01*
G02X-572559I-11693J0D01*
G01Y-104441D01*
G02X-549173I11693J12078D01*
G37*
G36*
G01X-1004542Y-44741D02*
G02X-997228Y-30548I1195J8365D01*
G02X-997385Y-42365I-6119J-5828D01*
G02X-1002317Y-44763I-5961J5989D01*
G03X-1002432Y-45725I65J-496D01*
G01X-1001004Y-46273D01*
X-999840Y-48771D01*
X-1000159Y-49787D01*
X-1003727Y-51451D01*
X-1004711Y-51043D01*
X-1005876Y-48545D01*
X-1004986Y-45958D01*
X-1004406Y-45688D01*
G03X-1004542Y-44741I-211J453D01*
G37*
G36*
G01X-961235D02*
G02X-953921Y-30548I1195J8365D01*
G02X-954078Y-42365I-6119J-5828D01*
G02X-959010Y-44763I-5961J5989D01*
G03X-959125Y-45725I65J-496D01*
G01X-957697Y-46273D01*
X-956533Y-48771D01*
X-956852Y-49787D01*
X-960420Y-51451D01*
X-961404Y-51043D01*
X-962569Y-48545D01*
X-961679Y-45958D01*
X-961099Y-45688D01*
G03X-961235Y-44741I-211J453D01*
G37*
G54D30*
X-1535063Y-22160D03*
X-1530063Y-12160D03*
Y-17160D03*
Y-22160D03*
X-1535063Y-12160D03*
Y-17160D03*
X-1515063Y-12160D03*
Y-17160D03*
Y-22160D03*
X-1525063Y-12160D03*
Y-17160D03*
X-1520063Y-12160D03*
Y-17160D03*
X-1525063Y-22160D03*
X-1520063D03*
X-1500063Y-12160D03*
Y-17160D03*
Y-22160D03*
X-1510063Y-12160D03*
Y-17160D03*
X-1505063Y-12160D03*
Y-17160D03*
X-1510063Y-22160D03*
X-1505063D03*
X-1485063Y-12160D03*
Y-17160D03*
Y-22160D03*
X-1495063Y-12160D03*
Y-17160D03*
X-1490063Y-12160D03*
Y-17160D03*
X-1495063Y-22160D03*
X-1490063D03*
X-1475063D03*
X-1470063Y-12160D03*
Y-17160D03*
Y-22160D03*
X-1480063Y-12160D03*
Y-17160D03*
X-1475063Y-12160D03*
Y-17160D03*
X-1480063Y-22160D03*
X-1450000Y-112500D03*
X-1465063Y-12160D03*
Y-17160D03*
Y-22160D03*
X-1437500Y-175000D03*
X-1450000Y-162500D03*
Y-137500D03*
X-1437500Y-100000D03*
X-1436500Y-87500D03*
X-1450000D03*
X-1435000Y1000D03*
X-1425000Y-162500D03*
X-1430500Y-93500D03*
X-1430000Y-75400D03*
X-1421250Y-81250D03*
X-1431500Y-81000D03*
X-1419500Y-18000D03*
X-1420000Y14500D03*
X-1412500Y-175000D03*
X-1406250Y-106250D03*
X-1412000Y-100500D03*
X-1418500Y-93500D03*
X-1406250Y-82500D03*
X-1412500Y-62500D03*
X-1387500Y-175000D03*
Y-150000D03*
X-1400000Y-162500D03*
X-1387300Y-133200D03*
X-1387500Y-125000D03*
X-1400100Y-131550D03*
X-1395000Y-106250D03*
X-1400000Y-112500D03*
X-1400500Y-96500D03*
X-1393750Y-82500D03*
X-1400000Y-75000D03*
X-1387500Y-62500D03*
X-1394500Y-18000D03*
X-1395000Y-500D03*
X-1395518Y14053D03*
X-1371250Y-112500D03*
X-1380000Y-106250D03*
X-1381250Y-82500D03*
X-1375000Y-75000D03*
X-1373800Y-52900D03*
X-1382500Y-8000D03*
Y7000D03*
X-1363750Y-106250D03*
X-1356250Y-82500D03*
X-1368750D03*
X-1362500Y-62500D03*
X-1356700Y-25600D03*
X-1357500Y-8000D03*
X-1370000Y-500D03*
X-1357500Y7000D03*
X-1370000Y14500D03*
X-1350600Y-75000D03*
X-1343200Y-82700D03*
X-1345000Y-500D03*
Y14500D03*
X-1330400Y-74900D03*
X-1337500Y-62500D03*
X-1332500Y-27500D03*
Y7000D03*
X-465000Y12500D03*
Y-37500D03*
X-462000Y-73500D03*
X-477500Y0D03*
Y-25000D03*
X-490000Y12500D03*
X-502500Y0D03*
X-490000Y-12500D03*
X-502500Y-25000D03*
X-490000Y-37500D03*
X-502500Y-65000D03*
X-490000Y-77500D03*
X-502500Y-90000D03*
X-490000Y-102500D03*
X-515000Y12500D03*
Y-12500D03*
Y-37500D03*
Y-77500D03*
Y-102500D03*
Y-127500D03*
Y-152500D03*
Y-177500D03*
X-527500Y0D03*
Y-25000D03*
Y-65000D03*
Y-90000D03*
Y-115000D03*
Y-140000D03*
Y-165000D03*
X-540000Y12500D03*
X-552500Y0D03*
X-540000Y-12500D03*
Y-37500D03*
X-552500Y-25000D03*
Y-65000D03*
X-540000Y-77500D03*
Y-102500D03*
Y-127500D03*
X-552500Y-140000D03*
X-540000Y-152500D03*
X-552500Y-165000D03*
X-540000Y-177500D03*
X-565000Y12500D03*
Y-12500D03*
Y-37500D03*
Y-152500D03*
Y-177500D03*
X-577500Y0D03*
Y-25000D03*
Y-65000D03*
Y-115000D03*
Y-140000D03*
Y-165000D03*
X-590000Y12500D03*
Y-12500D03*
Y-37500D03*
X-602500Y0D03*
Y-25000D03*
X-616000Y-25500D03*
X-630000Y-37500D03*
X-642500Y-12500D03*
Y-37500D03*
Y-25500D03*
X-655500D03*
X-672500Y-7500D03*
X-685000Y5000D03*
Y-20000D03*
Y-45000D03*
X-710000Y5000D03*
Y-20000D03*
X-697500Y-7500D03*
X-710000Y-45000D03*
X-722500Y-7500D03*
Y-57500D03*
X-735000Y5000D03*
Y-20000D03*
Y-45000D03*
X-747500Y-7500D03*
Y-57500D03*
X-760000Y5000D03*
X-772500Y-7500D03*
X-760000Y-20000D03*
Y-45000D03*
X-772500Y-57500D03*
X-760000Y-70000D03*
X-772500Y-82500D03*
X-760000Y-95000D03*
X-772500Y-107500D03*
X-760000Y-120000D03*
X-772500Y-132500D03*
X-760000Y-145000D03*
X-785000Y5000D03*
Y-20000D03*
X-797500Y-7500D03*
X-810000Y5000D03*
Y-20000D03*
X-835000D03*
X-822500Y-7500D03*
X-835000Y-45000D03*
X-822500Y-57500D03*
X-835000Y-70000D03*
X-822500Y-82500D03*
X-835000Y-95000D03*
X-822500Y-107500D03*
X-835000Y-120000D03*
X-822500Y-132500D03*
Y-159500D03*
X-847500Y-7500D03*
Y-57500D03*
Y-82500D03*
Y-107500D03*
Y-132500D03*
Y-159500D03*
X-860000Y5000D03*
Y-20000D03*
Y-45000D03*
Y-70000D03*
Y-95000D03*
Y-170000D03*
X-872500Y-7500D03*
Y-57500D03*
Y-82500D03*
Y-107500D03*
Y-132500D03*
Y-159500D03*
X-885000Y5000D03*
X-897500Y-7500D03*
X-885000Y-20000D03*
Y-45000D03*
X-897500Y-57500D03*
X-885000Y-70000D03*
X-897500Y-82500D03*
X-885000Y-95000D03*
X-897500Y-107500D03*
Y-132500D03*
Y-159500D03*
X-885000Y-170000D03*
X-910000Y5000D03*
Y-20000D03*
Y-45000D03*
Y-70000D03*
Y-95000D03*
Y-170000D03*
X-922500Y-7500D03*
Y-57500D03*
Y-82500D03*
Y-107500D03*
Y-132500D03*
Y-159500D03*
X-945000Y-7500D03*
X-970000D03*
X-997500D03*
X-1022140Y-122960D03*
X-1017670Y-123250D03*
G54D36*
X-951181Y-48187D03*
X-948228Y-53698D03*
X-951181Y-63147D03*
X-948228Y-68659D03*
X-951181Y-78108D03*
X-948228Y-83620D03*
Y-98580D03*
X-951181Y-93068D03*
X-991535Y-53698D03*
Y-68659D03*
Y-83620D03*
Y-98580D03*
X-994488Y-48187D03*
Y-63147D03*
Y-78108D03*
Y-93068D03*
G54D34*
X-793728Y-146102D03*
Y-153976D03*
G54D31*
X-1327756Y-175039D03*
Y-167165D03*
Y-159291D03*
Y-143543D03*
Y-135669D03*
Y-127795D03*
X-1319882Y-175039D03*
Y-167165D03*
Y-159291D03*
Y-135669D03*
Y-127795D03*
X-434055D03*
X-426181D03*
X-434055Y-135669D03*
X-426181D03*
Y-143543D03*
X-434055Y-159291D03*
X-426181D03*
X-434055Y-167165D03*
X-426181D03*
X-434055Y-175039D03*
X-426181D03*
X-793728Y-161850D03*
G54D35*
Y-138228D03*
G54D32*
X-785200Y-83100D03*
X-806854D03*
G54D33*
X-785200Y-99635D03*
X-806854D03*
G54D29*
X-1410000Y0D03*
G54D38*
X-486810Y-167165D03*
G54D37*
Y-118937D03*
%LPD*%
G75*
G54D10*
X-1639488Y-27500D03*
X-1644488D03*
X-1654488Y-27300D03*
X-1649488Y-27400D03*
X-1634488Y-27600D03*
X-1629488Y-27700D03*
X-1618400Y-71600D03*
X-1618300Y-63100D03*
X-1621600Y-61100D03*
Y-65100D03*
X-1618500Y-67200D03*
X-1621600Y-69400D03*
X-1615000Y-37500D03*
Y-27500D03*
Y-32500D03*
X-1610000Y-37500D03*
Y-32500D03*
Y-27500D03*
X-1600000Y-37500D03*
Y-27500D03*
Y-32500D03*
X-1605000Y-37500D03*
Y-32500D03*
Y-27500D03*
X-1595000Y-37500D03*
Y-32500D03*
Y-27500D03*
X-1580000Y-42500D03*
Y-47500D03*
X-1585000Y-42500D03*
Y-47500D03*
X-1590000D03*
Y-42500D03*
X-1580000Y-27500D03*
Y-32500D03*
Y-37500D03*
X-1585000Y-32500D03*
Y-27500D03*
Y-37500D03*
X-1590000D03*
Y-32500D03*
Y-27500D03*
X-1565000Y-42500D03*
Y-47500D03*
X-1575000Y-42500D03*
Y-47500D03*
X-1570000Y-42500D03*
Y-47500D03*
X-1565000Y-27500D03*
Y-32500D03*
Y-37500D03*
X-1575000Y-27500D03*
Y-32500D03*
Y-37500D03*
X-1570000Y-32500D03*
Y-27500D03*
Y-37500D03*
X-1555000Y-47500D03*
Y-42500D03*
X-1550000Y-47500D03*
Y-42500D03*
X-1560000D03*
Y-47500D03*
X-1545000D03*
Y-42500D03*
Y-37500D03*
Y-32500D03*
Y-27500D03*
X-1555000Y-37500D03*
Y-32500D03*
Y-27500D03*
X-1550000Y-37500D03*
Y-32500D03*
Y-27500D03*
X-1560000D03*
Y-32500D03*
Y-37500D03*
X-1535000Y-42500D03*
Y-47500D03*
X-1540000Y-42500D03*
Y-47500D03*
Y-37500D03*
Y-32500D03*
X-1535000Y-37500D03*
Y-32500D03*
X-1486693Y-151890D03*
Y-156890D03*
Y-136890D03*
Y-131890D03*
Y-111890D03*
Y-116890D03*
Y-91890D03*
Y-96890D03*
X-1481693Y-166890D03*
Y-161890D03*
Y-141890D03*
Y-146890D03*
Y-121890D03*
Y-126890D03*
Y-101890D03*
Y-106890D03*
Y-86890D03*
Y-81890D03*
X-1452000Y-74000D03*
Y-78200D03*
X-1452100Y-82200D03*
X-1451700Y-65700D03*
X-1451500Y-61800D03*
X-1451800Y-69600D03*
X-1450000Y-175000D03*
X-1437500Y-162500D03*
X-1450000Y-150000D03*
Y-125000D03*
X-1443500Y-94000D03*
X-1450000Y-100000D03*
X-1449100Y-71800D03*
X-1448900Y-76100D03*
X-1449000Y-80300D03*
X-1448800Y-63800D03*
X-1448700Y-59900D03*
X-1448800Y-67700D03*
X-1434892Y-40389D03*
Y-50389D03*
Y-45389D03*
Y-35389D03*
X-1425000Y-175000D03*
X-1424500Y-100000D03*
X-1425000Y-87500D03*
Y-62500D03*
X-1419892Y-50389D03*
Y-40389D03*
Y-45389D03*
X-1427392Y-50389D03*
Y-45389D03*
Y-40389D03*
X-1419892Y-35389D03*
X-1427392D03*
X-1432000Y-18000D03*
X-1412500Y-162500D03*
X-1412000Y-87000D03*
X-1412500Y-75000D03*
X-1404892Y-50389D03*
Y-45389D03*
Y-40389D03*
X-1412392Y-50389D03*
Y-45389D03*
Y-40389D03*
X-1404892Y-35389D03*
X-1412392D03*
X-1407000Y-18000D03*
X-1407500Y14500D03*
X-1400000Y-175000D03*
X-1387500Y-162500D03*
X-1400000Y-150000D03*
X-1387500Y-137500D03*
X-1400000Y-125000D03*
X-1387500Y-112500D03*
X-1400500Y-87000D03*
X-1391000Y-96500D03*
X-1387500Y-75000D03*
X-1400000Y-62500D03*
X-1389892Y-40389D03*
Y-45389D03*
Y-50389D03*
X-1397392Y-40389D03*
Y-45389D03*
Y-50389D03*
X-1389892Y-35389D03*
X-1397392D03*
X-1395000Y-8000D03*
X-1375000Y-62500D03*
X-1382392Y-40389D03*
Y-45389D03*
Y-50389D03*
Y-35389D03*
X-1382500Y-18000D03*
Y-500D03*
Y14500D03*
X-1362500Y-75000D03*
X-1370000Y-8000D03*
X-1357500Y-500D03*
X-1370000Y7000D03*
X-1357500Y14500D03*
X-1350000Y-62500D03*
X-1345000Y-8000D03*
Y7000D03*
X-1335400Y-75000D03*
Y-37600D03*
X-1332500Y-500D03*
Y14500D03*
X-1322228Y-88400D03*
X-1321000Y-94850D03*
X-1317700Y-60200D03*
X-1310559Y-68700D03*
X-1311200Y-30200D03*
X-1318500Y-6000D03*
X-1306850Y-95000D03*
X-1297995Y-58405D03*
X-1298400Y-63200D03*
X-1298780Y-52200D03*
X-1298000Y-41200D03*
X-1298700Y-35700D03*
X-1295400Y-13400D03*
X-1279429Y-180579D03*
X-1276860Y-178030D03*
X-1248860Y-150200D03*
X-1249016Y-144800D03*
X-1250660Y-140480D03*
X-1236310Y-140390D03*
X-1202580Y-176300D03*
X-1202100Y-103200D03*
X-1191200Y-40500D03*
X-1191000Y-46500D03*
X-1192359Y-5800D03*
X-1172500Y-44000D03*
X-1173200Y-49700D03*
X-1178900Y-46700D03*
X-1172500Y-38500D03*
X-1178950Y-23250D03*
X-1178800Y-34800D03*
X-1177800Y-12100D03*
X-1178800Y-5800D03*
X-1154200Y-103100D03*
X-1160150Y-26750D03*
X-1158700Y-16250D03*
X-1159700Y-5750D03*
X-1125000Y-101700D03*
X-1121870Y-104330D03*
X-1115490Y-104240D03*
X-1118701Y-101759D03*
X-1112402Y-101600D03*
X-1109300Y-104200D03*
X-1106102Y-102100D03*
X-1107700Y-73400D03*
Y-63100D03*
X-1107800Y-68200D03*
X-1102953Y-104200D03*
X-1063600Y-56600D03*
X-1062000Y-29200D03*
X-1061900Y-5200D03*
X-1015729Y-100550D03*
X-1012638Y-85886D03*
X-1015179Y-74100D03*
X-1012638Y-70873D03*
Y-56060D03*
X-1012860Y-41250D03*
X-1012500Y-7500D03*
X-1003380Y-86986D03*
X-1008429Y-91400D03*
X-999960Y-90706D03*
X-996670Y-75460D03*
X-1008719Y-75998D03*
X-999860Y-75848D03*
Y-60885D03*
X-1003780Y-56060D03*
X-994280Y-40890D03*
X-1007500Y14500D03*
X-983000Y-7500D03*
X-982500Y14500D03*
X-969331Y-100849D03*
Y-85886D03*
X-965512Y-90706D03*
X-971779Y-73800D03*
X-965412Y-75848D03*
Y-45922D03*
X-956653Y-90706D03*
X-960273Y-101049D03*
X-953250Y-75340D03*
X-956553Y-75848D03*
X-957779Y-57700D03*
X-956553Y-60885D03*
Y-45922D03*
X-957500Y-7500D03*
Y14500D03*
X-932500Y-7500D03*
Y14500D03*
X-922500Y-170000D03*
Y-120000D03*
Y-95000D03*
Y-70000D03*
Y-45000D03*
Y-20000D03*
Y5000D03*
X-910000Y-159500D03*
Y-132500D03*
Y-107500D03*
Y-82500D03*
Y-57500D03*
Y-7500D03*
X-909500Y14500D03*
X-897500Y-170000D03*
X-885000Y-159500D03*
Y-132500D03*
Y-107500D03*
X-897500Y-95000D03*
X-885000Y-82500D03*
X-897500Y-70000D03*
X-885000Y-57500D03*
X-897500Y-45000D03*
X-885000Y-7500D03*
X-897500Y-20000D03*
Y5000D03*
X-885000Y14500D03*
X-872500Y-170000D03*
Y-95000D03*
Y-70000D03*
Y-45000D03*
Y-20000D03*
Y5000D03*
X-860000Y-159500D03*
Y-132500D03*
Y-107500D03*
Y-82500D03*
Y-57500D03*
Y-7500D03*
Y14500D03*
X-847500Y-170000D03*
Y-95000D03*
Y-70000D03*
Y-45000D03*
Y-20000D03*
Y5000D03*
X-822500Y-170000D03*
X-835000Y-159500D03*
X-822500Y-145000D03*
X-835000Y-132500D03*
X-822500Y-120000D03*
X-835000Y-107500D03*
X-822500Y-95000D03*
X-835000Y-82500D03*
X-822500Y-70000D03*
X-835000Y-57500D03*
X-822500Y-45000D03*
Y-20000D03*
Y5000D03*
X-835500Y14500D03*
X-810000Y-170000D03*
Y-157500D03*
Y-145000D03*
Y-132500D03*
Y-120000D03*
Y-70000D03*
Y-57500D03*
Y-45000D03*
Y-7500D03*
Y14500D03*
X-797500Y-120000D03*
Y-70000D03*
Y-57500D03*
Y-45000D03*
Y-20000D03*
Y5000D03*
X-785500Y-120000D03*
X-785000Y-70000D03*
Y-57500D03*
Y-45000D03*
Y-7500D03*
Y14500D03*
X-772500Y-170000D03*
Y-145000D03*
X-760000Y-132500D03*
X-772500Y-120000D03*
X-760000Y-107500D03*
X-772500Y-95000D03*
X-760000Y-82500D03*
X-772500Y-70000D03*
X-760000Y-57500D03*
X-772500Y-45000D03*
X-760000Y-7500D03*
X-772500Y-20000D03*
Y5000D03*
X-760000Y14500D03*
X-747500Y-45000D03*
Y-20000D03*
Y5000D03*
X-735000Y-57500D03*
Y-7500D03*
Y14500D03*
X-722500Y-45000D03*
Y-20000D03*
Y5000D03*
X-697500Y-45000D03*
Y-20000D03*
X-710000Y-7500D03*
X-697500Y5000D03*
X-710000Y14500D03*
X-685000Y-7500D03*
Y14500D03*
X-672500Y-45000D03*
Y-20000D03*
Y5000D03*
X-655500Y-37500D03*
Y-12500D03*
Y-500D03*
X-660000Y14500D03*
X-632500D03*
X-616614Y-151890D03*
Y-156890D03*
Y-136890D03*
Y-131890D03*
Y-111890D03*
Y-116890D03*
Y-91890D03*
Y-96890D03*
X-616000Y-37500D03*
X-630000Y-25500D03*
Y-12500D03*
X-616000D03*
Y14500D03*
X-611614Y-166890D03*
Y-161890D03*
Y-141890D03*
Y-146890D03*
Y-121890D03*
Y-126890D03*
Y-101890D03*
Y-106890D03*
Y-86890D03*
Y-81890D03*
X-602500Y-37500D03*
Y-12500D03*
Y12500D03*
X-590000Y-25000D03*
Y0D03*
X-577500Y-177500D03*
Y-152500D03*
Y-127500D03*
Y-37500D03*
Y-12500D03*
Y12500D03*
X-565000Y-165000D03*
Y-140000D03*
Y-65000D03*
Y-25000D03*
Y0D03*
X-540000Y-165000D03*
X-552500Y-177500D03*
Y-152500D03*
X-540000Y-140000D03*
Y-115000D03*
Y-90000D03*
Y-65000D03*
Y-25000D03*
X-552500Y-37500D03*
Y-12500D03*
X-540000Y0D03*
X-552500Y12500D03*
X-527500Y-177500D03*
Y-152500D03*
Y-127500D03*
Y-102500D03*
Y-77500D03*
Y-37500D03*
Y-12500D03*
Y12500D03*
X-515000Y-165000D03*
Y-140000D03*
Y-115000D03*
Y-90000D03*
Y-65000D03*
Y-25000D03*
Y0D03*
X-502500Y-102500D03*
X-490000Y-90000D03*
X-502500Y-77500D03*
Y-37500D03*
Y-12500D03*
X-490000Y0D03*
X-502500Y12500D03*
X-486421Y-26159D03*
X-477500Y-37500D03*
Y12500D03*
X-465000Y-25000D03*
X-461441Y6559D03*
X-452700Y-69000D03*
X-442800Y-46600D03*
X-432118Y-87082D03*
X-441959Y-68600D03*
X-429000Y-57600D03*
X-430700Y-63100D03*
X-430180Y-52100D03*
X-429400Y-41100D03*
X-430400Y-35600D03*
X-424600Y-14400D03*
X-405540Y-183080D03*
Y-179630D03*
X-380421Y-147000D03*
X-389600Y-123640D03*
X-389770Y-127220D03*
X-373620Y-124430D03*
X-333450Y-174950D03*
X-321700Y-42000D03*
X-321500Y-47500D03*
X-321800Y-7300D03*
X-303200Y-43300D03*
X-309400Y-47700D03*
Y-25100D03*
X-308500Y-36400D03*
X-308800Y-7400D03*
X-302500Y-15200D03*
X-307900Y-13628D03*
X-286500Y-113700D03*
X-296400Y-113500D03*
X-289500Y-32500D03*
X-290800Y-26000D03*
X-290300Y-4400D03*
X-278100Y-178200D03*
X-282300Y-113700D03*
X-254921Y-101700D03*
X-245411Y-104240D03*
X-248622Y-101759D03*
X-251792Y-104330D03*
X-242323Y-101600D03*
X-239222Y-104200D03*
X-236024Y-102100D03*
X-232874Y-104200D03*
G54D20*
G01X-1174900Y-473500D02*
X-1171300Y-466100D01*
X-1171800Y-465700D01*
X-1175900Y-473200D01*
X-1176200Y-471200D01*
X-1172500Y-465400D01*
X-1175700Y-471300D01*
X-1176500Y-469800D01*
X-1172900Y-464900D01*
X-1173600Y-451800D01*
X-1173700Y-449900D01*
X-1182100D01*
X-1187400Y-473000D01*
X-1182400D01*
X-1177800Y-456000D01*
X-1177000Y-455900D01*
X-1176100Y-468500D01*
X-1173700Y-464500D01*
X-1174600Y-450800D01*
X-1181500Y-450900D01*
X-1186400Y-472100D01*
X-1183100D01*
X-1178300Y-454800D01*
X-1176600Y-455000D01*
X-1175500Y-466300D01*
X-1174600Y-464300D01*
X-1175400Y-451700D01*
X-1181000Y-451800D01*
X-1185300Y-471300D01*
X-1183800Y-471400D01*
X-1179000Y-454300D01*
X-1176200D01*
X-1175200Y-462200D01*
X-1176200Y-452500D01*
X-1180500Y-452800D01*
X-1184300Y-470600D01*
X-1179700Y-453400D01*
X-1176800D01*
G01X-1182820Y-448900D02*
X-1188360Y-473900D01*
X-1181580D01*
X-1177300Y-456700D01*
X-1176920Y-473900D01*
X-1172260D01*
X-1163400Y-456920D01*
X-1167240Y-473900D01*
X-1160380D01*
X-1154840Y-448900D01*
X-1164540D01*
X-1172540Y-464820D01*
X-1172880Y-448900D01*
X-1182820D01*
G01X-1155800Y-449500D02*
X-1161100Y-472900D01*
X-1166100Y-473000D01*
X-1166000Y-471900D01*
X-1161800Y-472100D01*
X-1161300Y-471000D01*
X-1165900Y-471100D01*
X-1165700Y-470000D01*
X-1161300D01*
X-1160800Y-469200D01*
X-1165300Y-469100D01*
X-1165200Y-468100D01*
X-1160700D01*
X-1160400Y-467100D01*
X-1165100Y-467200D01*
X-1164900Y-466300D01*
X-1160300Y-466200D01*
X-1160000Y-465200D01*
X-1164700Y-465300D01*
X-1164400Y-464200D01*
X-1159700Y-464300D01*
X-1159300Y-463100D01*
X-1164700Y-463500D01*
X-1164000Y-462500D01*
X-1159500Y-462600D01*
X-1159000Y-461700D01*
X-1163900D01*
X-1163600Y-460600D01*
X-1159100Y-460800D01*
X-1158800Y-459900D01*
X-1163200D01*
X-1163100Y-459200D01*
X-1158800D01*
X-1158300Y-458500D01*
X-1163000Y-458400D01*
X-1162900Y-457800D01*
X-1158400Y-457900D01*
X-1158200Y-457200D01*
X-1162500Y-457000D01*
X-1163100Y-456500D01*
X-1157800D01*
X-1157500Y-455500D01*
X-1156600Y-449800D01*
X-1164000D01*
X-1164500Y-450700D01*
X-1157600D01*
X-1157800Y-451700D01*
X-1165000Y-451600D01*
X-1165400Y-452400D01*
X-1157900Y-452500D01*
X-1157800Y-453500D01*
X-1165900Y-453200D01*
X-1166200Y-453900D01*
X-1158000Y-454300D01*
X-1158300Y-455300D01*
X-1166600Y-454800D01*
X-1158900Y-455900D01*
X-1167000Y-455600D01*
X-1163500Y-456400D01*
X-1167300Y-456300D01*
X-1171700Y-465200D01*
X-1169200Y-466400D01*
X-1164500Y-457200D01*
X-1166900Y-457100D01*
X-1170600Y-465200D01*
X-1169500Y-465500D01*
X-1166000Y-457800D01*
G01X-1170300Y-466300D02*
X-1174000Y-473600D01*
G01X-1169500Y-466900D02*
X-1172800Y-473000D01*
G01X-1152800Y-456400D02*
X-1156600Y-473100D01*
X-1152200Y-473000D01*
X-1148300Y-456600D01*
X-1149500D01*
X-1152900Y-472000D01*
X-1155600Y-472300D01*
X-1152100Y-456500D01*
X-1150400Y-456400D01*
X-1153600Y-471200D01*
X-1154500Y-471400D01*
X-1151400Y-457200D01*
G01X-1153420Y-455700D02*
X-1157540Y-473900D01*
X-1151380D01*
X-1147440Y-455700D01*
X-1153420D01*
G01X-1151600Y-450100D02*
X-1146700Y-450000D01*
X-1147000Y-451000D01*
X-1151700D01*
G01X-1152020Y-448900D02*
X-1152660Y-451900D01*
X-1146380D01*
X-1145740Y-448900D01*
X-1152020D01*
G01X-1129400Y-468900D02*
X-1131800Y-471900D01*
X-1136500Y-473700D01*
X-1142100Y-473600D01*
X-1144600Y-472300D01*
X-1145800Y-471000D01*
X-1146400Y-469500D01*
X-1146700Y-467600D01*
X-1146500Y-464600D01*
X-1145400Y-461200D01*
X-1143500Y-459100D01*
X-1140200Y-456900D01*
X-1136100Y-456200D01*
X-1132300Y-456400D01*
X-1129400Y-457900D01*
X-1127500Y-460900D01*
X-1132500Y-461000D01*
X-1133400Y-459200D01*
X-1135100Y-458100D01*
X-1136800Y-458000D01*
X-1138600Y-458900D01*
X-1140300Y-460700D01*
X-1141800Y-463600D01*
X-1142400Y-466600D01*
X-1141500Y-470400D01*
X-1140200Y-471500D01*
X-1138300Y-471600D01*
X-1136300Y-471400D01*
X-1134500Y-469100D01*
X-1130300Y-469000D01*
X-1132500Y-471200D01*
X-1134900Y-472000D01*
X-1137200Y-472800D01*
X-1142300Y-472700D01*
X-1144900Y-470600D01*
X-1145800Y-467400D01*
X-1145500Y-465100D01*
X-1144700Y-462000D01*
X-1143300Y-460200D01*
X-1139800Y-457700D01*
X-1135400Y-457000D01*
X-1131300Y-457600D01*
X-1128800Y-460100D01*
X-1132100D01*
X-1134300Y-457900D01*
X-1130100Y-458800D01*
X-1129500Y-459400D01*
X-1132600Y-459000D01*
G01X-1133300Y-461900D02*
Y-461420D01*
X-1133640Y-460240D01*
X-1134300Y-459200D01*
X-1135200Y-458900D01*
X-1136580D01*
X-1138060Y-459820D01*
X-1139360Y-461000D01*
X-1140240Y-462220D01*
X-1140880Y-463920D01*
X-1141300Y-465380D01*
X-1141500Y-467060D01*
Y-468020D01*
X-1141020Y-469220D01*
X-1139780Y-470700D01*
X-1137160D01*
X-1135840Y-469500D01*
X-1134980Y-468200D01*
X-1134940Y-468100D01*
X-1128180D01*
X-1128240Y-468240D01*
X-1128840Y-469340D01*
X-1129020Y-469800D01*
X-1129740Y-470700D01*
X-1130500Y-471460D01*
X-1131660Y-472420D01*
X-1132820Y-473200D01*
X-1133740Y-473740D01*
X-1136380Y-474500D01*
X-1141640D01*
X-1142540Y-474320D01*
X-1144220Y-473760D01*
X-1144900Y-473240D01*
X-1146240Y-471900D01*
X-1146780Y-471180D01*
X-1146940Y-470880D01*
X-1147320Y-469660D01*
X-1147500Y-468640D01*
Y-464780D01*
X-1146940Y-462540D01*
X-1146380Y-461580D01*
X-1145980Y-460780D01*
X-1145420Y-459880D01*
X-1143700Y-458140D01*
X-1142740Y-457380D01*
X-1142000Y-456820D01*
X-1140240Y-456040D01*
X-1139500Y-455660D01*
X-1138800Y-455480D01*
X-1137260Y-455300D01*
X-1134320D01*
X-1132020Y-455500D01*
X-1130940Y-455860D01*
X-1130580Y-456020D01*
X-1129260Y-456780D01*
X-1128940Y-457100D01*
X-1127820Y-458420D01*
X-1127060Y-460300D01*
X-1126900Y-460800D01*
Y-461900D01*
X-1133300D01*
G01X-1137900Y-458000D02*
X-1140300Y-459100D01*
X-1142500Y-460900D01*
X-1143900Y-462600D01*
X-1144800Y-467600D01*
X-1144200Y-470000D01*
X-1141000Y-472300D01*
X-1136400Y-472200D01*
X-1131600Y-469600D01*
X-1135400Y-470400D01*
X-1141100Y-471400D01*
X-1142100Y-470700D01*
X-1142700Y-469000D01*
X-1143100Y-467100D01*
X-1142700Y-464100D01*
X-1140500Y-459900D01*
X-1143400Y-463700D01*
X-1143600Y-465700D01*
X-1143900Y-467700D01*
X-1143000Y-469900D01*
G01X-1113500Y-459200D02*
X-1123500Y-459300D01*
X-1123700Y-460100D01*
X-1114300Y-460000D01*
X-1116500Y-460800D01*
X-1124200Y-461000D01*
X-1124400Y-461900D01*
X-1117600Y-461800D01*
X-1118800Y-462800D01*
X-1124500Y-462700D01*
X-1124600Y-463600D01*
X-1119300Y-463700D01*
X-1120100Y-464800D01*
X-1125000Y-464600D01*
Y-465500D01*
X-1120600Y-465700D01*
X-1120800Y-466700D01*
X-1125300Y-466500D01*
X-1125500Y-467400D01*
X-1121000Y-467600D01*
X-1121200Y-468700D01*
X-1125600Y-468400D01*
X-1125900Y-469100D01*
X-1121500Y-469500D01*
X-1121700Y-470700D01*
X-1126100Y-470000D01*
X-1126200Y-470700D01*
X-1121900Y-471200D01*
X-1122100Y-472000D01*
X-1126300Y-471700D01*
X-1126700Y-472300D01*
X-1122100Y-472700D01*
X-1122200Y-473100D01*
X-1126800Y-473200D01*
G01X-1114060Y-460760D02*
X-1114840Y-460920D01*
X-1115740Y-461140D01*
X-1116880Y-461820D01*
X-1117700Y-462640D01*
X-1118620Y-463340D01*
X-1118840Y-464020D01*
X-1119440Y-464820D01*
X-1119660Y-465480D01*
X-1120060Y-466280D01*
X-1120280Y-466960D01*
X-1120480Y-468360D01*
X-1120680Y-468940D01*
X-1120880Y-469940D01*
X-1121080Y-470540D01*
X-1121700Y-472980D01*
X-1121820Y-473900D01*
X-1127640D01*
X-1126920Y-471060D01*
X-1126720Y-470440D01*
X-1126500Y-468800D01*
X-1126320Y-467860D01*
X-1126120Y-467260D01*
X-1125920Y-466260D01*
X-1125720Y-465660D01*
X-1125300Y-464000D01*
X-1125120Y-462220D01*
X-1124920Y-461660D01*
X-1124720Y-460660D01*
X-1124520Y-460060D01*
X-1123720Y-456800D01*
X-1123580Y-455700D01*
X-1117880D01*
X-1118100Y-456160D01*
Y-458740D01*
X-1116500Y-457160D01*
X-1115780Y-456620D01*
X-1114680Y-456060D01*
X-1113560Y-455680D01*
X-1112460Y-455500D01*
X-1111720D01*
X-1112460Y-458440D01*
X-1114060Y-460760D01*
G01X-1123100Y-456500D02*
X-1118900Y-456600D01*
X-1118800Y-457600D01*
X-1123100Y-457500D01*
X-1123300Y-458500D01*
X-1113100Y-458400D01*
X-1112600Y-456400D01*
X-1116100Y-457600D01*
X-1113500D01*
G01X-1105100Y-471100D02*
X-1104060D01*
X-1103780Y-470820D01*
X-1103200Y-470640D01*
X-1102080Y-469740D01*
X-1100800Y-468240D01*
X-1100380Y-467400D01*
X-1100180Y-467100D01*
X-1099960Y-466660D01*
X-1099540Y-465720D01*
X-1099320Y-465060D01*
X-1099100Y-464180D01*
Y-461220D01*
X-1099360Y-460200D01*
X-1099660Y-459900D01*
X-1100700Y-458640D01*
X-1101220Y-458300D01*
X-1103340D01*
X-1103700Y-458640D01*
X-1105300Y-459840D01*
X-1105760Y-460320D01*
X-1106180Y-460940D01*
X-1107060Y-462020D01*
X-1107260Y-462880D01*
X-1107660Y-463660D01*
X-1108100Y-465000D01*
Y-468640D01*
X-1107620Y-469600D01*
X-1107140Y-470340D01*
X-1105980Y-471100D01*
X-1105100D01*
G01X-1112540Y-460460D02*
X-1110680Y-458140D01*
X-1109940Y-457580D01*
X-1109000Y-456840D01*
X-1108480Y-456660D01*
X-1107940Y-456400D01*
X-1107740Y-456200D01*
X-1107480Y-456060D01*
X-1106880Y-455860D01*
X-1106480Y-455660D01*
X-1105960Y-455480D01*
X-1104600Y-455300D01*
X-1103440Y-455100D01*
X-1100940D01*
X-1098240Y-455480D01*
X-1097720Y-455660D01*
X-1097020Y-456020D01*
X-1096180Y-456640D01*
X-1095620Y-456820D01*
X-1095540Y-456900D01*
X-1094200Y-458440D01*
X-1093660Y-459520D01*
X-1093460Y-460100D01*
X-1093100Y-461020D01*
Y-464400D01*
X-1093420Y-465360D01*
X-1094300Y-465520D01*
X-1094720Y-465740D01*
X-1095320Y-465940D01*
X-1096120Y-466340D01*
X-1096720Y-466540D01*
X-1097100Y-466720D01*
X-1098100Y-466920D01*
X-1098520Y-467140D01*
X-1099160Y-467360D01*
X-1101180Y-468700D01*
X-1094660D01*
X-1095220Y-469800D01*
X-1095560Y-470320D01*
X-1097480Y-472220D01*
X-1099940Y-473740D01*
X-1102580Y-474500D01*
X-1108800D01*
X-1109300Y-474340D01*
X-1111220Y-473560D01*
X-1111720Y-473240D01*
X-1113240Y-471720D01*
X-1113560Y-471240D01*
X-1113760Y-470660D01*
X-1114140Y-469980D01*
X-1114320Y-469120D01*
X-1114500Y-468680D01*
Y-464980D01*
X-1114320Y-464260D01*
X-1114140Y-463720D01*
X-1113940Y-463320D01*
X-1113720Y-462660D01*
X-1113560Y-462000D01*
X-1111880Y-460320D01*
X-1112540Y-460460D01*
G01X-1099300Y-466400D02*
X-1093800Y-464400D01*
X-1093900Y-461100D01*
X-1094800Y-459000D01*
X-1096800Y-457300D01*
X-1100000Y-456100D01*
X-1102800Y-455900D01*
X-1106300Y-456300D01*
X-1109600Y-458100D01*
X-1111400Y-460500D01*
X-1112900Y-462600D01*
X-1113600Y-465600D01*
X-1113500Y-469100D01*
X-1112100Y-471900D01*
X-1109600Y-473300D01*
X-1105700Y-473800D01*
X-1101000Y-473400D01*
X-1098200Y-471800D01*
X-1096600Y-470100D01*
X-1096000Y-469500D01*
X-1100800Y-469700D01*
X-1102300Y-471100D01*
X-1097900Y-470400D01*
X-1100300Y-471800D01*
X-1103200Y-471400D01*
X-1100600Y-472600D01*
X-1103000D01*
X-1103700Y-471900D01*
X-1103400Y-473000D01*
X-1104600Y-471900D01*
X-1106200D01*
X-1104100Y-473100D01*
X-1107200Y-472700D01*
X-1110100Y-472100D01*
X-1111500Y-470900D01*
X-1112600Y-468600D01*
X-1112700Y-466000D01*
X-1112400Y-463700D01*
X-1111400Y-461600D01*
X-1109600Y-459500D01*
X-1108100Y-458200D01*
X-1105900Y-457200D01*
X-1102200Y-456700D01*
X-1099600Y-457300D01*
X-1097000Y-458400D01*
X-1095500Y-459500D01*
X-1094600Y-461900D01*
X-1094500Y-463900D01*
X-1098800Y-465200D01*
X-1098600Y-464000D01*
X-1095100Y-463100D01*
X-1095300Y-462000D01*
X-1098500Y-463000D01*
X-1098600Y-461700D01*
X-1095600Y-461300D01*
X-1095900Y-460200D01*
X-1098400Y-460700D01*
X-1098900Y-459900D01*
X-1096600Y-459400D01*
X-1097100Y-458900D01*
X-1099400Y-459000D01*
X-1098800Y-458500D01*
X-1100600Y-458000D01*
X-1102400Y-457400D01*
X-1104200Y-457500D01*
X-1106200Y-458100D01*
X-1107900Y-459000D01*
X-1110500Y-462200D01*
X-1111800Y-464800D01*
Y-467700D01*
X-1110700Y-470300D01*
X-1108700Y-472000D01*
X-1106600Y-471900D01*
X-1107900Y-470300D01*
X-1108900Y-468700D01*
Y-465500D01*
X-1107900Y-462300D01*
X-1106500Y-459900D01*
X-1104100Y-458200D01*
X-1108000Y-460000D01*
X-1108100Y-461500D01*
X-1108700Y-461200D01*
X-1110300Y-463600D01*
X-1111000Y-466000D01*
X-1110700Y-468100D01*
X-1109500Y-470600D01*
X-1107700Y-471400D01*
X-1109300Y-469100D01*
X-1109800Y-467600D01*
X-1108600Y-462200D01*
X-1110400Y-466800D01*
G01X-1113600Y-460900D02*
X-1112100Y-459000D01*
G01X-1093100Y-469400D02*
X-1087900Y-469700D01*
X-1086500Y-471400D01*
X-1083400Y-472300D01*
X-1081000Y-472000D01*
X-1079300Y-470600D01*
X-1079000Y-468900D01*
X-1079500Y-467700D01*
X-1080300Y-466600D01*
X-1081800Y-466000D01*
X-1083300Y-465500D01*
X-1085300Y-465000D01*
X-1087900Y-464000D01*
X-1089100Y-463200D01*
X-1089800Y-461000D01*
X-1089500Y-459000D01*
X-1088600Y-457700D01*
X-1086500Y-456700D01*
X-1084600Y-456100D01*
X-1081900Y-455900D01*
X-1079900Y-455800D01*
X-1076900Y-456300D01*
X-1075000Y-457000D01*
X-1073700Y-458000D01*
X-1073300Y-459400D01*
X-1077600Y-459500D01*
X-1078100Y-458800D01*
X-1074300Y-458500D01*
X-1074600Y-457800D01*
X-1078200Y-458200D01*
X-1076000Y-457400D01*
X-1079100Y-457700D01*
X-1077100Y-456900D01*
X-1080100Y-457300D01*
X-1079200Y-456600D01*
X-1083100Y-456800D01*
X-1080600Y-457300D01*
X-1083400Y-457700D01*
X-1083600Y-457000D01*
X-1087900Y-458400D01*
X-1084000Y-458100D01*
X-1088600Y-459100D01*
X-1088800Y-461500D01*
X-1087700Y-463600D01*
X-1084400Y-464300D01*
X-1081200Y-465400D01*
X-1078800Y-467300D01*
X-1078300Y-470500D01*
X-1079900Y-472600D01*
X-1083500Y-473300D01*
X-1085600Y-472600D01*
X-1088800Y-470500D01*
X-1092600Y-470200D01*
X-1092100Y-471800D01*
X-1091700Y-471300D01*
X-1089300Y-471500D01*
X-1091300Y-472300D01*
X-1088700Y-471600D01*
X-1084000Y-473500D01*
X-1089100D01*
X-1091000Y-472900D01*
X-1087200Y-472800D01*
X-1082700Y-473700D01*
X-1079000Y-473600D01*
X-1076500Y-472300D01*
X-1074700Y-470600D01*
X-1074300Y-467300D01*
X-1074800Y-465300D01*
X-1078800Y-463600D01*
X-1081600Y-462900D01*
X-1083400Y-462500D01*
X-1084800Y-461500D01*
X-1085000Y-458900D01*
X-1088100Y-459800D01*
X-1087200Y-462700D01*
X-1085000Y-463400D01*
X-1082000Y-464100D01*
X-1079600Y-465100D01*
X-1078200Y-466500D01*
X-1077700Y-468500D01*
X-1077500Y-470100D01*
X-1079200Y-472800D01*
X-1076800Y-471400D01*
X-1075300Y-470000D01*
X-1077300Y-470900D01*
X-1075000Y-468800D01*
X-1075200Y-466100D01*
X-1082700Y-462700D01*
X-1084200Y-462900D01*
X-1086600Y-461800D01*
X-1087200Y-460300D01*
X-1085800Y-459800D01*
X-1086600Y-461000D01*
X-1085300Y-460400D01*
X-1085600Y-461400D01*
X-1076700Y-466500D01*
X-1075900Y-467100D01*
X-1075700Y-468400D01*
X-1076800Y-469500D01*
X-1077800Y-466200D01*
X-1075900Y-468800D01*
G01X-1093780Y-468700D02*
X-1087100D01*
Y-469740D01*
X-1086800Y-470060D01*
X-1086520Y-470600D01*
X-1085820Y-470820D01*
X-1085660Y-471000D01*
X-1085120Y-471260D01*
X-1084400Y-471500D01*
X-1082360D01*
X-1080540Y-470600D01*
X-1080100Y-470140D01*
Y-469780D01*
X-1079840Y-469380D01*
X-1080380Y-467740D01*
X-1081440Y-466940D01*
X-1082560Y-466720D01*
X-1085740Y-465920D01*
X-1086940Y-465520D01*
X-1087600Y-465360D01*
X-1087740Y-465200D01*
X-1088540Y-464800D01*
X-1089140Y-464200D01*
X-1089540Y-464000D01*
X-1089800Y-463740D01*
X-1090000Y-463340D01*
X-1090180Y-463180D01*
X-1090500Y-462200D01*
Y-459800D01*
X-1090320Y-459260D01*
X-1090140Y-458500D01*
X-1090000Y-458260D01*
X-1089000Y-457260D01*
X-1088860Y-456940D01*
X-1085920Y-455480D01*
X-1083620Y-455100D01*
X-1082060Y-454900D01*
X-1080520D01*
X-1078580Y-455100D01*
X-1076240Y-455480D01*
X-1075120Y-455860D01*
X-1074800Y-456020D01*
X-1073680Y-456760D01*
X-1073160Y-457300D01*
X-1072620Y-458020D01*
X-1072500Y-458240D01*
Y-460300D01*
X-1078500D01*
Y-459200D01*
X-1079580Y-458380D01*
X-1080160Y-458100D01*
X-1082380D01*
X-1083280Y-458360D01*
X-1084020Y-458940D01*
X-1084340Y-459900D01*
X-1084060Y-460720D01*
X-1083740Y-461340D01*
X-1081860Y-462280D01*
X-1079400Y-462500D01*
X-1078660Y-462680D01*
X-1078100Y-462860D01*
X-1076500Y-463460D01*
X-1075320Y-463860D01*
X-1075060Y-464000D01*
X-1073820Y-465220D01*
X-1073480Y-466260D01*
X-1073300Y-467160D01*
Y-468420D01*
X-1073860Y-470700D01*
X-1074000Y-470960D01*
X-1075140Y-472300D01*
X-1075280Y-472440D01*
X-1076600Y-473380D01*
X-1077320Y-473740D01*
X-1079600Y-474500D01*
X-1088240D01*
X-1089160Y-474320D01*
X-1089920Y-474120D01*
X-1090860Y-473760D01*
X-1091560Y-473400D01*
X-1092700Y-472460D01*
X-1093180Y-471980D01*
X-1093340Y-471480D01*
X-1093520Y-471100D01*
X-1093700Y-470320D01*
X-1093780Y-468700D01*
G01X-1095100D02*
X-1092800D01*
G01X-1058300Y-469400D02*
X-1055400Y-467100D01*
X-1053900Y-463700D01*
X-1054400Y-461200D01*
X-1055900Y-459900D01*
X-1054800Y-463500D01*
X-1055400Y-463600D01*
X-1054600Y-464500D01*
X-1055700D01*
X-1055400Y-465300D01*
X-1056200Y-466800D01*
G01X-1059300Y-457700D02*
X-1059100Y-455600D01*
X-1055200Y-456300D01*
X-1052700Y-457900D01*
X-1051100Y-460800D01*
X-1050900Y-465200D01*
X-1052900Y-469400D01*
X-1055300Y-471900D01*
X-1059000Y-473500D01*
X-1066000D01*
X-1068000Y-471900D01*
X-1070200Y-468700D01*
X-1070600Y-464500D01*
X-1069000Y-460500D01*
X-1066000Y-457500D01*
X-1063000Y-456500D01*
X-1059200Y-456000D01*
X-1053000Y-458500D01*
X-1052000Y-461500D01*
Y-465700D01*
X-1053400Y-468600D01*
X-1055700Y-471000D01*
X-1058900Y-472600D01*
X-1063700Y-473000D01*
X-1065900Y-473600D01*
X-1068300Y-472900D01*
X-1070600Y-469300D01*
X-1065100Y-472600D01*
X-1060800Y-472200D01*
X-1057200Y-470700D01*
X-1055200Y-469100D01*
X-1053300Y-466500D01*
X-1052500Y-463400D01*
X-1052900Y-460100D01*
X-1057000Y-457400D01*
X-1058700Y-457200D01*
X-1057000Y-458500D01*
X-1055100Y-459800D01*
X-1053800Y-460900D01*
X-1053400Y-463100D01*
X-1053600Y-465600D01*
X-1054800Y-467500D01*
X-1056400Y-469200D01*
X-1058500Y-470200D01*
X-1060200Y-470700D01*
X-1061500Y-471400D01*
X-1063300Y-471600D01*
X-1065400Y-471500D01*
X-1069000Y-469300D01*
X-1069600Y-466400D01*
X-1069700Y-463700D01*
X-1068600Y-461200D01*
X-1066700Y-459200D01*
X-1063900Y-457600D01*
X-1061100Y-457000D01*
X-1059600D01*
X-1060200Y-457500D01*
X-1063300Y-458000D01*
X-1065300Y-459500D01*
X-1066900Y-460600D01*
X-1067900Y-462100D01*
X-1068800Y-464300D01*
X-1068700Y-466900D01*
X-1068200Y-469100D01*
X-1066900Y-470200D01*
X-1064300Y-470900D01*
X-1065700Y-469300D01*
X-1065800Y-465900D01*
X-1065300Y-462900D01*
X-1061200Y-458200D01*
X-1063600Y-458900D01*
X-1066400Y-461300D01*
X-1067800Y-464200D01*
Y-467200D01*
X-1067400Y-469300D01*
X-1066300Y-469700D01*
X-1067100Y-466400D01*
X-1066600Y-463400D01*
X-1064700Y-460000D01*
X-1062600Y-458800D01*
X-1065300Y-461700D01*
X-1066700Y-467400D01*
G01X-1060840Y-455100D02*
X-1057160D01*
X-1055260Y-455480D01*
X-1054740Y-455640D01*
X-1053380Y-456420D01*
X-1052660Y-456800D01*
X-1052020Y-457420D01*
X-1051820Y-458020D01*
X-1051200Y-458660D01*
X-1051000Y-459060D01*
X-1050840Y-459200D01*
X-1050700Y-459780D01*
Y-460140D01*
X-1050400Y-460460D01*
X-1050280Y-460680D01*
X-1050100Y-461740D01*
Y-464240D01*
X-1050280Y-465160D01*
X-1050480Y-465980D01*
X-1050680Y-467120D01*
X-1051220Y-468180D01*
X-1051840Y-469020D01*
X-1052040Y-469600D01*
X-1052740Y-470500D01*
X-1054480Y-472240D01*
X-1055000Y-472580D01*
X-1055420Y-472780D01*
X-1056220Y-473380D01*
X-1056920Y-473740D01*
X-1059380Y-474500D01*
X-1065600D01*
X-1067860Y-473740D01*
X-1068160Y-473600D01*
X-1069500Y-472460D01*
X-1069820Y-472120D01*
X-1070380Y-471200D01*
X-1071140Y-469860D01*
X-1071300Y-469400D01*
Y-464580D01*
X-1071120Y-463880D01*
X-1070740Y-462900D01*
X-1070540Y-462320D01*
X-1069980Y-461000D01*
X-1068840Y-459500D01*
X-1066900Y-457560D01*
X-1066180Y-457020D01*
X-1065400Y-456620D01*
X-1064440Y-456040D01*
X-1063500Y-455660D01*
X-1062940Y-455480D01*
X-1060840Y-455100D01*
G01X-1057800Y-458580D02*
X-1057000Y-459120D01*
X-1056760Y-459840D01*
X-1056340Y-460460D01*
X-1056100Y-461640D01*
Y-463760D01*
X-1056320Y-464860D01*
X-1056720Y-466060D01*
X-1056940Y-466920D01*
X-1057200Y-467460D01*
X-1057640Y-467880D01*
X-1058040Y-468480D01*
X-1059960Y-470420D01*
X-1061020Y-470840D01*
X-1061420Y-471100D01*
X-1062720D01*
X-1063340Y-470840D01*
X-1063860Y-470600D01*
X-1064360Y-470080D01*
X-1064820Y-469400D01*
X-1065100Y-468840D01*
Y-464920D01*
X-1064880Y-464120D01*
X-1064420Y-462780D01*
X-1064160Y-462520D01*
X-1063620Y-461700D01*
X-1063200Y-460840D01*
X-1062500Y-460140D01*
X-1062120Y-459860D01*
X-1061720Y-459360D01*
X-1060600Y-458580D01*
X-1060040Y-458300D01*
X-1058360D01*
X-1057800Y-458580D01*
G01X-1040300Y-459100D02*
X-1041400Y-464800D01*
G01X-1044800Y-458200D02*
X-1041400D01*
X-1044300Y-472700D01*
X-1047400Y-472300D01*
X-1044100Y-458800D01*
X-1042400Y-459100D01*
X-1045100Y-471900D01*
X-1046500D01*
X-1043400Y-459700D01*
X-1045600Y-471500D01*
G01X-1036600Y-449900D02*
X-1036800Y-451300D01*
X-1038600Y-452400D01*
X-1039800Y-456100D01*
X-1033700Y-456500D01*
X-1032300Y-452100D01*
X-1028400Y-452000D01*
X-1028900Y-455400D01*
X-1027200Y-456600D01*
X-1025900Y-456800D01*
X-1026200Y-458200D01*
X-1030000Y-458400D01*
X-1031800Y-468900D01*
X-1030400Y-471700D01*
X-1029400D01*
X-1029600Y-473300D01*
X-1033100Y-473400D01*
X-1036100Y-472800D01*
X-1036200Y-470500D01*
X-1035900Y-467100D01*
X-1034400Y-461400D01*
X-1033800Y-458800D01*
X-1033500Y-458400D01*
X-1035000Y-458200D01*
X-1039600D01*
X-1040800Y-458300D01*
X-1043600Y-473200D01*
X-1048000Y-473000D01*
X-1045100Y-459400D01*
X-1044900Y-458400D01*
X-1048700D01*
X-1048100Y-456600D01*
X-1044900Y-456400D01*
X-1045200Y-457700D01*
X-1047600Y-457500D01*
X-1026500D01*
G01X-1049580Y-459100D02*
X-1048740Y-455700D01*
X-1044900D01*
Y-454780D01*
X-1044720Y-454060D01*
X-1044340Y-452920D01*
X-1043940Y-452120D01*
X-1043740Y-451520D01*
X-1043600Y-451260D01*
X-1042340Y-450000D01*
X-1042080Y-449860D01*
X-1040580Y-449480D01*
X-1039440Y-449300D01*
X-1036140D01*
X-1035440Y-449400D01*
X-1035480Y-449540D01*
X-1035680Y-450360D01*
X-1035880Y-451280D01*
X-1036000Y-451900D01*
X-1036740D01*
X-1037060Y-452200D01*
X-1037860Y-452600D01*
X-1038220Y-452980D01*
X-1038480Y-453740D01*
X-1038960Y-455700D01*
X-1034020D01*
X-1033720Y-455080D01*
X-1033500Y-453400D01*
X-1032940Y-451100D01*
X-1027260D01*
X-1027280Y-451180D01*
X-1027480Y-452780D01*
X-1027860Y-454280D01*
X-1028100Y-454760D01*
Y-455700D01*
X-1024800D01*
X-1024880Y-455940D01*
X-1025080Y-456940D01*
X-1025280Y-457540D01*
X-1025480Y-458560D01*
X-1025620Y-459100D01*
X-1029100D01*
Y-460000D01*
X-1029280Y-460540D01*
X-1029480Y-461540D01*
X-1029680Y-462140D01*
X-1029880Y-462960D01*
X-1030100Y-464000D01*
X-1030280Y-465560D01*
X-1030480Y-466140D01*
X-1030680Y-467140D01*
X-1030880Y-467740D01*
X-1031040Y-468400D01*
X-1031300Y-468660D01*
Y-469800D01*
X-1030300Y-470560D01*
X-1029940Y-470900D01*
X-1028220D01*
X-1028680Y-472780D01*
X-1028880Y-474120D01*
Y-474140D01*
X-1030720Y-474300D01*
X-1032860D01*
X-1034380Y-474120D01*
X-1035860Y-473740D01*
X-1036640Y-473280D01*
X-1036960Y-472660D01*
X-1037100Y-472280D01*
Y-470160D01*
X-1036920Y-469260D01*
X-1036700Y-468640D01*
X-1036500Y-466840D01*
X-1036320Y-466260D01*
X-1036120Y-465260D01*
X-1035920Y-464660D01*
X-1035720Y-463660D01*
X-1035520Y-463060D01*
X-1035320Y-462060D01*
X-1035120Y-461440D01*
X-1034820Y-459100D01*
X-1039900D01*
Y-460220D01*
X-1040280Y-461780D01*
X-1040480Y-463380D01*
X-1041280Y-466540D01*
X-1041480Y-467140D01*
X-1041700Y-468200D01*
X-1041880Y-469760D01*
X-1042080Y-470340D01*
X-1042280Y-471360D01*
X-1042480Y-472140D01*
X-1042680Y-472740D01*
X-1042880Y-473740D01*
X-1042940Y-473900D01*
X-1049140D01*
X-1048300Y-470620D01*
X-1048100Y-469020D01*
X-1047920Y-468260D01*
X-1047720Y-467660D01*
X-1047520Y-466660D01*
X-1047320Y-466060D01*
X-1047120Y-465060D01*
X-1046920Y-464460D01*
X-1046700Y-463400D01*
X-1046500Y-462020D01*
X-1046140Y-460500D01*
X-1045900Y-460040D01*
Y-459100D01*
X-1049580D01*
G01X-1038400Y-451100D02*
X-1040600Y-455800D01*
X-1043300D01*
X-1041400Y-451300D01*
X-1038900Y-451000D01*
X-1041200Y-455000D01*
X-1042000Y-455100D01*
X-1040500Y-452000D01*
G01X-1037500Y-449800D02*
X-1037800Y-451000D01*
X-1038500Y-450100D01*
X-1042000Y-450700D01*
X-1043100Y-452300D01*
X-1044100Y-455100D01*
X-1044200Y-456600D01*
X-1036600Y-456800D01*
G01X-1031100Y-472500D02*
X-1031400Y-470900D01*
X-1031900Y-472200D01*
X-1035200D01*
Y-467600D01*
X-1032000Y-453700D01*
X-1030500Y-453800D01*
X-1030000Y-456700D01*
X-1033400Y-471900D01*
X-1034300Y-471600D01*
X-1034200Y-467100D01*
X-1031400Y-454500D01*
X-1030700Y-456500D01*
X-1033700Y-470600D01*
X-1032700Y-461100D01*
G01X-1032000Y-452900D02*
X-1029300D01*
X-1028000Y-457000D01*
X-1029500Y-453600D01*
X-1029100Y-457300D01*
X-1032800Y-472800D01*
X-1030200Y-472600D01*
G54D11*
X-1608110Y-161654D03*
Y-156142D03*
X-1600236Y-151024D03*
Y-156535D03*
X-1592362Y-156142D03*
Y-161654D03*
X-1584488Y-151024D03*
Y-156535D03*
X-1576614Y-156142D03*
Y-161654D03*
X-1568740Y-151024D03*
Y-156535D03*
X-1560866Y-156142D03*
Y-161654D03*
X-1552992Y-151024D03*
Y-156535D03*
X-1545118Y-156142D03*
Y-161654D03*
X-1189134Y-134488D03*
Y-140000D03*
Y-145512D03*
X-1181260Y-151417D03*
X-1173386Y-151024D03*
X-1181260Y-156929D03*
X-1173386Y-156535D03*
Y-162047D03*
X-1181260Y-134882D03*
X-1165512Y-151417D03*
Y-134882D03*
X-1014488Y-178976D03*
Y-162441D03*
Y-145906D03*
Y-129370D03*
X-1006614Y-167559D03*
X-998740Y-178976D03*
X-1006614Y-151024D03*
X-998740Y-162441D03*
X-1006614Y-134488D03*
X-998740Y-145906D03*
Y-129370D03*
X-990866Y-167559D03*
X-982992Y-178976D03*
X-990866Y-151024D03*
X-982992Y-162441D03*
X-990866Y-134488D03*
X-982992Y-145906D03*
Y-129370D03*
X-975118Y-167559D03*
Y-151024D03*
Y-134488D03*
X-738032Y-161654D03*
Y-156142D03*
X-730157Y-151024D03*
Y-156535D03*
X-714409Y-151024D03*
X-722283Y-156142D03*
X-714409Y-156535D03*
X-722283Y-161654D03*
X-698661Y-151024D03*
X-706535Y-156142D03*
X-698661Y-156535D03*
X-706535Y-161654D03*
X-682913Y-151024D03*
X-690787Y-156142D03*
X-682913Y-156535D03*
X-690787Y-161654D03*
X-675039Y-156142D03*
Y-161654D03*
X-319055Y-134488D03*
Y-140000D03*
X-311181Y-151417D03*
X-303307Y-151024D03*
X-311181Y-156929D03*
Y-134882D03*
X-303307Y-140000D03*
X-295433Y-151417D03*
Y-134882D03*
Y-140394D03*
G54D21*
G01X-1186050Y-540000D02*
Y-552500D01*
X-1180250D01*
G01X-1174975D02*
X-1171350Y-540000D01*
X-1167725Y-552500D01*
G01X-1169030Y-548125D02*
X-1173670D01*
G01X-1159550Y-552500D02*
Y-546875D01*
X-1162450Y-540000D01*
G01X-1156650D02*
X-1159550Y-546875D01*
G01X-1144850Y-552500D02*
X-1150650D01*
Y-540000D01*
X-1144850D01*
G01X-1147170Y-546042D02*
X-1150650D01*
G01X-1138850Y-552500D02*
Y-540000D01*
X-1135225D01*
X-1134065Y-540625D01*
X-1133340Y-541458D01*
X-1133050Y-543125D01*
X-1133340Y-544792D01*
X-1134210Y-545833D01*
X-1135225Y-546458D01*
X-1138850D01*
G01X-1135225D02*
X-1133050Y-552500D01*
G01X-1115540Y-550000D02*
X-1114670Y-551459D01*
X-1113510Y-552292D01*
X-1112205Y-552500D01*
X-1111045Y-552292D01*
X-1109885Y-551250D01*
X-1109160Y-550000D01*
X-1109015Y-548750D01*
X-1109305Y-547292D01*
X-1110320Y-546250D01*
X-1111335Y-545833D01*
X-1112640D01*
G01X-1111335D02*
X-1110465Y-545208D01*
X-1109740Y-544167D01*
X-1109450Y-542917D01*
X-1109740Y-541667D01*
X-1110465Y-540625D01*
X-1111770Y-540000D01*
X-1113075Y-540208D01*
X-1114380Y-541042D01*
G54D12*
X-1356889Y-167165D03*
Y-118937D03*
X-1051613Y-167165D03*
Y-118937D03*
X-486810Y-167165D03*
Y-118937D03*
X-181534Y-167165D03*
Y-118937D03*
G54D22*
G01X-1185925Y-592500D02*
X-1178575Y-577500D01*
G01X-1185925D02*
X-1178575Y-592500D01*
G01X-1168050D02*
X-1166825Y-592250D01*
X-1165425Y-591500D01*
X-1164550Y-590250D01*
X-1164200Y-588500D01*
X-1164550Y-586750D01*
X-1165600Y-585250D01*
X-1167175Y-584500D01*
X-1168925D01*
X-1169975Y-584000D01*
X-1170850Y-582750D01*
X-1171200Y-581000D01*
X-1170675Y-579250D01*
X-1169450Y-578000D01*
X-1168050Y-577500D01*
X-1166650Y-578000D01*
X-1165425Y-579250D01*
X-1164900Y-581000D01*
X-1165250Y-582750D01*
X-1166125Y-584000D01*
X-1167175Y-584500D01*
X-1168925D01*
X-1170500Y-585250D01*
X-1171550Y-586750D01*
X-1171900Y-588500D01*
X-1171550Y-590250D01*
X-1170675Y-591500D01*
X-1169275Y-592250D01*
X-1168050Y-592500D01*
G01X-1153850D02*
X-1152625Y-592250D01*
X-1151225Y-591500D01*
X-1150350Y-590250D01*
X-1150000Y-588500D01*
X-1150350Y-586750D01*
X-1151400Y-585250D01*
X-1152975Y-584500D01*
X-1154725D01*
X-1155775Y-584000D01*
X-1156650Y-582750D01*
X-1157000Y-581000D01*
X-1156475Y-579250D01*
X-1155250Y-578000D01*
X-1153850Y-577500D01*
X-1152450Y-578000D01*
X-1151225Y-579250D01*
X-1150700Y-581000D01*
X-1151050Y-582750D01*
X-1151925Y-584000D01*
X-1152975Y-584500D01*
X-1154725D01*
X-1156300Y-585250D01*
X-1157350Y-586750D01*
X-1157700Y-588500D01*
X-1157350Y-590250D01*
X-1156475Y-591500D01*
X-1155075Y-592250D01*
X-1153850Y-592500D01*
G01X-1140000D02*
X-1139650Y-589250D01*
X-1139125Y-586500D01*
X-1138425Y-584000D01*
X-1137550Y-581250D01*
X-1136150Y-577500D01*
X-1143150D01*
G01X-1129300Y-590250D02*
X-1128250Y-591500D01*
X-1127025Y-592250D01*
X-1125450Y-592500D01*
X-1123875Y-592000D01*
X-1122650Y-591000D01*
X-1121775Y-589250D01*
X-1121600Y-587250D01*
X-1121950Y-585250D01*
X-1122825Y-584000D01*
X-1124050Y-583000D01*
X-1125275Y-582750D01*
X-1126500Y-583000D01*
X-1128075Y-584000D01*
X-1127550Y-577500D01*
X-1122825D01*
G01X-1111600Y-592500D02*
X-1111250Y-589250D01*
X-1110725Y-586500D01*
X-1110025Y-584000D01*
X-1109150Y-581250D01*
X-1107750Y-577500D01*
X-1114750D01*
G01X-1097050Y-592500D02*
Y-577500D01*
X-1099150Y-580500D01*
G01Y-592500D02*
X-1094950D01*
G01X-1085125Y-587500D02*
X-1080575D01*
G01X-1068650Y-577500D02*
X-1070050Y-578000D01*
X-1071100Y-579250D01*
X-1071800Y-580750D01*
X-1072325Y-582750D01*
X-1072500Y-585000D01*
X-1072325Y-587250D01*
X-1071800Y-589250D01*
X-1071100Y-590750D01*
X-1070050Y-592000D01*
X-1068650Y-592500D01*
X-1067250Y-592000D01*
X-1066200Y-590750D01*
X-1065500Y-589250D01*
X-1064975Y-587250D01*
X-1064800Y-585000D01*
X-1064975Y-582750D01*
X-1065500Y-580750D01*
X-1066200Y-579250D01*
X-1067250Y-578000D01*
X-1068650Y-577500D01*
G01X-1054450D02*
X-1055850Y-578000D01*
X-1056900Y-579250D01*
X-1057600Y-580750D01*
X-1058125Y-582750D01*
X-1058300Y-585000D01*
X-1058125Y-587250D01*
X-1057600Y-589250D01*
X-1056900Y-590750D01*
X-1055850Y-592000D01*
X-1054450Y-592500D01*
X-1053050Y-592000D01*
X-1052000Y-590750D01*
X-1051300Y-589250D01*
X-1050775Y-587250D01*
X-1050600Y-585000D01*
X-1050775Y-582750D01*
X-1051300Y-580750D01*
X-1052000Y-579250D01*
X-1053050Y-578000D01*
X-1054450Y-577500D01*
G01X-1044100Y-590250D02*
X-1043050Y-591500D01*
X-1041825Y-592250D01*
X-1040250Y-592500D01*
X-1038675Y-592000D01*
X-1037450Y-591000D01*
X-1036575Y-589250D01*
X-1036400Y-587250D01*
X-1036750Y-585250D01*
X-1037625Y-584000D01*
X-1038850Y-583000D01*
X-1040075Y-582750D01*
X-1041300Y-583000D01*
X-1042875Y-584000D01*
X-1042350Y-577500D01*
X-1037625D01*
G01X-911875Y-592500D02*
X-907500Y-577500D01*
X-903125Y-592500D01*
G01X-904700Y-587250D02*
X-910300D01*
G01X-810781Y-103562D02*
X-806854Y-99635D01*
G01D02*
X-802927Y-95708D01*
G01X-810781D02*
X-806854Y-99635D01*
G01D02*
X-802927Y-103562D01*
G01X-796771Y-141271D02*
X-793728Y-138228D01*
G01D02*
X-790685Y-135185D01*
G01X-796771D02*
X-793728Y-138228D01*
G01D02*
X-790685Y-141271D01*
G01X-789127Y-103562D02*
X-785200Y-99635D01*
G01X-789127Y-95708D02*
X-785200Y-99635D01*
G01D02*
X-781273Y-103562D01*
G01X-785200Y-99635D02*
X-781273Y-95708D01*
G54D13*
X-1296260Y-175039D03*
X-1304134D03*
X-1296260Y-167165D03*
X-1304134D03*
X-1296260Y-159291D03*
X-1304134D03*
X-1296260Y-143543D03*
X-1304134D03*
X-1296260Y-135669D03*
X-1304134D03*
X-1296260Y-127795D03*
X-1304134D03*
X-793728Y-138228D03*
X-457677Y-175039D03*
Y-167165D03*
Y-159291D03*
Y-143543D03*
Y-135669D03*
Y-127795D03*
X-449803Y-175039D03*
Y-167165D03*
Y-159291D03*
Y-143543D03*
Y-135669D03*
Y-127795D03*
G54D23*
G01X-1200000Y-560000D02*
X-890000D01*
G01Y-520000D02*
X-1200000D01*
G01X-575000Y-480000D02*
X-1200000D01*
G01X-927500Y-560000D02*
Y-600000D01*
G01X-915000Y-440000D02*
Y-480000D01*
G01X-890000D02*
Y-600000D01*
G01X-870000Y-440000D02*
Y-480000D01*
G01X-680000D02*
Y-440000D01*
G01X-1200000Y-600000D02*
X-575000D01*
Y-440000D01*
X-1200000D01*
Y-600000D01*
G54D14*
X-1025000Y-50942D03*
Y1459D03*
X-1015157Y-105312D03*
X-997441D03*
X-981693Y-50942D03*
Y1459D03*
X-971850Y-105312D03*
X-954134D03*
X-938386Y-50942D03*
Y1459D03*
G54D24*
G01X-1481693Y-81890D02*
X-1483618Y-83815D01*
X-1501056D01*
X-1518021Y-66850D01*
X-1581311D01*
X-1604686Y-90225D01*
Y-157798D01*
X-1605211Y-158323D01*
X-1605929D01*
X-1608110Y-156142D01*
G01X-1481693Y-86890D02*
X-1483618Y-84965D01*
X-1501532D01*
X-1518497Y-68000D01*
X-1580835D01*
X-1603536Y-90701D01*
Y-158274D01*
X-1604735Y-159473D01*
X-1605929D01*
X-1608110Y-161654D01*
G01X-1486693Y-91890D02*
X-1488618Y-93815D01*
X-1498746D01*
X-1521611Y-70950D01*
X-1577439D01*
X-1596936Y-90447D01*
Y-146879D01*
X-1597055Y-146998D01*
Y-152705D01*
X-1597555Y-153205D01*
X-1598055D01*
X-1600236Y-151024D01*
G01X-1486693Y-96890D02*
X-1488618Y-94965D01*
X-1499223D01*
X-1522087Y-72100D01*
X-1576963D01*
X-1595786Y-90923D01*
Y-147355D01*
X-1595905Y-147474D01*
Y-153181D01*
X-1597079Y-154355D01*
X-1598055D01*
X-1600236Y-156535D01*
G01X-1486693Y-111890D02*
X-1488618Y-113815D01*
X-1497378D01*
X-1513629Y-97564D01*
Y-94032D01*
X-1528611Y-79050D01*
X-1566970D01*
X-1581188Y-93268D01*
Y-152585D01*
X-1581807Y-153205D01*
X-1582307D01*
X-1584488Y-151024D01*
G01X-1481693Y-101890D02*
X-1483618Y-103815D01*
X-1491903D01*
X-1495184Y-100534D01*
X-1495520Y-100197D01*
X-1500711D01*
X-1525908Y-75000D01*
X-1573424D01*
X-1589009Y-90585D01*
Y-157736D01*
X-1589596Y-158323D01*
X-1590181D01*
X-1592362Y-156142D01*
G01X-1486693Y-116890D02*
X-1488618Y-114965D01*
X-1497854D01*
X-1514779Y-98040D01*
Y-94508D01*
X-1529087Y-80200D01*
X-1566494D01*
X-1580038Y-93745D01*
Y-153062D01*
X-1581331Y-154355D01*
X-1582307D01*
X-1584488Y-156535D01*
G01X-1481693Y-106890D02*
X-1483618Y-104965D01*
X-1492379D01*
X-1495997Y-101347D01*
X-1501187D01*
X-1526384Y-76150D01*
X-1572947D01*
X-1587859Y-91061D01*
Y-158212D01*
X-1589120Y-159473D01*
X-1590181D01*
X-1592362Y-161654D01*
G01X-1576614Y-156142D02*
X-1574433Y-158323D01*
X-1573606D01*
X-1573190Y-157907D01*
Y-93054D01*
X-1563286Y-83150D01*
X-1532764D01*
X-1520900Y-95014D01*
Y-98921D01*
X-1499178Y-120642D01*
X-1495708D01*
X-1495035Y-121316D01*
X-1492536Y-123815D01*
X-1483618D01*
X-1481693Y-121890D01*
G01X-1568740Y-151024D02*
X-1566559Y-153205D01*
X-1566059D01*
X-1565316Y-152461D01*
Y-94278D01*
X-1558288Y-87250D01*
X-1536260D01*
X-1527000Y-96510D01*
Y-106733D01*
X-1499918Y-133815D01*
X-1488618D01*
X-1486693Y-131890D01*
G01X-1576614Y-161654D02*
X-1574433Y-159473D01*
X-1573129D01*
X-1572040Y-158384D01*
Y-93531D01*
X-1562809Y-84300D01*
X-1533240D01*
X-1522050Y-95490D01*
Y-99397D01*
X-1499655Y-121792D01*
X-1496185D01*
X-1493012Y-124965D01*
X-1483618D01*
X-1481693Y-126890D01*
G01X-1568740Y-156535D02*
X-1566559Y-154355D01*
X-1565583D01*
X-1564166Y-152938D01*
Y-94754D01*
X-1557812Y-88400D01*
X-1536737D01*
X-1528150Y-96987D01*
Y-107209D01*
X-1500394Y-134965D01*
X-1488618D01*
X-1486693Y-136890D01*
G01X-1560866Y-156142D02*
X-1558685Y-158323D01*
X-1557764D01*
X-1557442Y-158000D01*
Y-93719D01*
X-1555123Y-91400D01*
X-1539426D01*
X-1531600Y-99226D01*
Y-110823D01*
X-1501804Y-140619D01*
X-1494301D01*
X-1493628Y-141292D01*
X-1491105Y-143815D01*
X-1483618D01*
X-1481693Y-141890D01*
G01X-1552992Y-151024D02*
X-1550811Y-153205D01*
X-1549950D01*
X-1549568Y-152823D01*
Y-98787D01*
X-1547274Y-96494D01*
X-1543116D01*
X-1543115Y-96493D01*
X-1542163D01*
X-1537262Y-101395D01*
Y-116416D01*
X-1499863Y-153815D01*
X-1488618D01*
X-1486693Y-151890D01*
G01X-1560866Y-161654D02*
X-1558685Y-159473D01*
X-1557288D01*
X-1556292Y-158477D01*
Y-94195D01*
X-1554647Y-92550D01*
X-1539902D01*
X-1532750Y-99702D01*
Y-111299D01*
X-1502281Y-141769D01*
X-1494778D01*
X-1491582Y-144965D01*
X-1483618D01*
X-1481693Y-146890D01*
G01X-1552992Y-156535D02*
X-1550811Y-154355D01*
X-1549474D01*
X-1548418Y-153299D01*
Y-99264D01*
X-1546798Y-97644D01*
X-1542639D01*
X-1538412Y-101871D01*
Y-116892D01*
X-1500339Y-154965D01*
X-1488618D01*
X-1486693Y-156890D01*
G01X-1481693Y-161890D02*
X-1483618Y-163815D01*
X-1487985D01*
X-1498669Y-174499D01*
X-1525344D01*
X-1541520Y-158323D01*
X-1542937D01*
X-1545118Y-156142D01*
G01X-1481693Y-166890D02*
X-1483618Y-164965D01*
X-1487509D01*
X-1498192Y-175649D01*
X-1525820D01*
X-1541996Y-159473D01*
X-1542937D01*
X-1545118Y-161654D01*
G01X-1007500Y-470000D02*
X-1006450Y-475000D01*
X-1005250Y-470000D01*
X-1004050Y-475000D01*
X-1003000Y-470000D01*
G01X-1001125Y-475000D02*
X-999250Y-470000D01*
X-997375Y-475000D01*
G01X-998050Y-473250D02*
X-1000450D01*
G01X-994825Y-474333D02*
X-994225Y-474750D01*
X-993550Y-475000D01*
X-992950D01*
X-992350Y-474750D01*
X-991900Y-474333D01*
X-991675Y-473750D01*
X-991825Y-473167D01*
X-992200Y-472667D01*
X-992875Y-472333D01*
X-993775Y-472167D01*
X-994300Y-471833D01*
X-994525Y-471250D01*
X-994375Y-470667D01*
X-994000Y-470250D01*
X-993475Y-470000D01*
X-992950D01*
X-992425Y-470167D01*
X-991975Y-470583D01*
G01X-988825Y-475000D02*
Y-470000D01*
G01X-985675D02*
Y-475000D01*
G01Y-472500D02*
X-988825D01*
G01X-976525Y-474417D02*
X-976000Y-474833D01*
X-975400Y-475000D01*
X-974800Y-474833D01*
X-974275Y-474333D01*
X-973900Y-473583D01*
X-973750Y-472833D01*
Y-471917D01*
X-973900Y-471167D01*
X-974275Y-470500D01*
X-974725Y-470167D01*
X-975250Y-470000D01*
X-975850Y-470167D01*
X-976300Y-470500D01*
X-976600Y-471000D01*
X-976750Y-471667D01*
X-976600Y-472250D01*
X-976225Y-472833D01*
X-975775Y-473167D01*
X-975250Y-473250D01*
X-974650Y-473083D01*
X-974200Y-472667D01*
X-973750Y-471917D01*
G01X-969250Y-475000D02*
X-968725Y-474917D01*
X-968125Y-474667D01*
X-967750Y-474250D01*
X-967600Y-473667D01*
X-967750Y-473083D01*
X-968200Y-472583D01*
X-968875Y-472333D01*
X-969625D01*
X-970075Y-472167D01*
X-970450Y-471750D01*
X-970600Y-471167D01*
X-970375Y-470583D01*
X-969850Y-470167D01*
X-969250Y-470000D01*
X-968650Y-470167D01*
X-968125Y-470583D01*
X-967900Y-471167D01*
X-968050Y-471750D01*
X-968425Y-472167D01*
X-968875Y-472333D01*
X-969625D01*
X-970300Y-472583D01*
X-970750Y-473083D01*
X-970900Y-473667D01*
X-970750Y-474250D01*
X-970375Y-474667D01*
X-969775Y-474917D01*
X-969250Y-475000D01*
G01X-963250Y-470000D02*
X-963850Y-470167D01*
X-964300Y-470583D01*
X-964600Y-471083D01*
X-964825Y-471750D01*
X-964900Y-472500D01*
X-964825Y-473250D01*
X-964600Y-473917D01*
X-964300Y-474417D01*
X-963850Y-474833D01*
X-963250Y-475000D01*
X-962650Y-474833D01*
X-962200Y-474417D01*
X-961900Y-473917D01*
X-961675Y-473250D01*
X-961600Y-472500D01*
X-961675Y-471750D01*
X-961900Y-471083D01*
X-962200Y-470583D01*
X-962650Y-470167D01*
X-963250Y-470000D01*
G01X-958900Y-474250D02*
X-958450Y-474667D01*
X-957925Y-474917D01*
X-957250Y-475000D01*
X-956575Y-474833D01*
X-956050Y-474500D01*
X-955675Y-473917D01*
X-955600Y-473250D01*
X-955750Y-472583D01*
X-956125Y-472167D01*
X-956650Y-471833D01*
X-957175Y-471750D01*
X-957700Y-471833D01*
X-958375Y-472167D01*
X-958150Y-470000D01*
X-956125D01*
G01X-952675Y-470833D02*
X-952225Y-470333D01*
X-951700Y-470083D01*
X-951100Y-470000D01*
X-950350Y-470167D01*
X-949825Y-470583D01*
X-949675Y-471083D01*
X-949750Y-471583D01*
X-950050Y-472000D01*
X-951550Y-472833D01*
X-952225Y-473417D01*
X-952675Y-474250D01*
X-952825Y-475000D01*
X-949675D01*
G01X-946225Y-473333D02*
X-944275D01*
G01X-940675Y-472917D02*
X-940150Y-472333D01*
X-939700Y-472000D01*
X-939100Y-471833D01*
X-938575Y-472000D01*
X-938200Y-472333D01*
X-937900Y-472833D01*
X-937825Y-473417D01*
X-937900Y-473917D01*
X-938200Y-474417D01*
X-938650Y-474833D01*
X-939175Y-475000D01*
X-939775Y-474833D01*
X-940300Y-474333D01*
X-940600Y-473583D01*
X-940675Y-472750D01*
X-940525Y-471667D01*
X-940300Y-471083D01*
X-939925Y-470500D01*
X-939400Y-470083D01*
X-938875Y-470000D01*
X-938350Y-470167D01*
X-937975Y-470583D01*
G01X-934900Y-474000D02*
X-934450Y-474583D01*
X-933850Y-474917D01*
X-933175Y-475000D01*
X-932575Y-474917D01*
X-931975Y-474500D01*
X-931600Y-474000D01*
X-931525Y-473500D01*
X-931675Y-472917D01*
X-932200Y-472500D01*
X-932725Y-472333D01*
X-933400D01*
G01X-932725D02*
X-932275Y-472083D01*
X-931900Y-471667D01*
X-931750Y-471167D01*
X-931900Y-470667D01*
X-932275Y-470250D01*
X-932950Y-470000D01*
X-933625Y-470083D01*
X-934300Y-470417D01*
G01X-928525Y-474417D02*
X-928000Y-474833D01*
X-927400Y-475000D01*
X-926800Y-474833D01*
X-926275Y-474333D01*
X-925900Y-473583D01*
X-925750Y-472833D01*
Y-471917D01*
X-925900Y-471167D01*
X-926275Y-470500D01*
X-926725Y-470167D01*
X-927250Y-470000D01*
X-927850Y-470167D01*
X-928300Y-470500D01*
X-928600Y-471000D01*
X-928750Y-471667D01*
X-928600Y-472250D01*
X-928225Y-472833D01*
X-927775Y-473167D01*
X-927250Y-473250D01*
X-926650Y-473083D01*
X-926200Y-472667D01*
X-925750Y-471917D01*
G01X-922525Y-474417D02*
X-922000Y-474833D01*
X-921400Y-475000D01*
X-920800Y-474833D01*
X-920275Y-474333D01*
X-919900Y-473583D01*
X-919750Y-472833D01*
Y-471917D01*
X-919900Y-471167D01*
X-920275Y-470500D01*
X-920725Y-470167D01*
X-921250Y-470000D01*
X-921850Y-470167D01*
X-922300Y-470500D01*
X-922600Y-471000D01*
X-922750Y-471667D01*
X-922600Y-472250D01*
X-922225Y-472833D01*
X-921775Y-473167D01*
X-921250Y-473250D01*
X-920650Y-473083D01*
X-920200Y-472667D01*
X-919750Y-471917D01*
G01X-1006750Y-465000D02*
Y-460000D01*
X-1004875D01*
X-1004275Y-460250D01*
X-1003900Y-460583D01*
X-1003750Y-461250D01*
X-1003900Y-461917D01*
X-1004350Y-462333D01*
X-1004875Y-462583D01*
X-1006750D01*
G01X-1004875D02*
X-1003750Y-465000D01*
G01X-997750D02*
X-1000750D01*
Y-460000D01*
X-997750D01*
G01X-998950Y-462417D02*
X-1000750D01*
G01X-994900Y-465000D02*
Y-460000D01*
X-993400D01*
X-992800Y-460250D01*
X-992350Y-460583D01*
X-991975Y-461083D01*
X-991675Y-461667D01*
X-991600Y-462500D01*
X-991675Y-463333D01*
X-991975Y-463917D01*
X-992350Y-464417D01*
X-992800Y-464750D01*
X-993400Y-465000D01*
X-994900D01*
G01X-989200D02*
Y-460000D01*
X-987250Y-464167D01*
X-985300Y-460000D01*
Y-465000D01*
G01X-981250D02*
X-981850Y-464917D01*
X-982375Y-464583D01*
X-982825Y-464083D01*
X-983125Y-463500D01*
X-983275Y-462833D01*
Y-462167D01*
X-983125Y-461500D01*
X-982825Y-460917D01*
X-982375Y-460417D01*
X-981850Y-460083D01*
X-981250Y-460000D01*
X-980650Y-460083D01*
X-980125Y-460417D01*
X-979675Y-460917D01*
X-979375Y-461500D01*
X-979225Y-462167D01*
Y-462833D01*
X-979375Y-463500D01*
X-979675Y-464083D01*
X-980125Y-464583D01*
X-980650Y-464917D01*
X-981250Y-465000D01*
G01X-976975D02*
Y-460000D01*
X-973525Y-465000D01*
Y-460000D01*
G01X-970900Y-465000D02*
Y-460000D01*
X-969400D01*
X-968800Y-460250D01*
X-968350Y-460583D01*
X-967975Y-461083D01*
X-967675Y-461667D01*
X-967600Y-462500D01*
X-967675Y-463333D01*
X-967975Y-463917D01*
X-968350Y-464417D01*
X-968800Y-464750D01*
X-969400Y-465000D01*
X-970900D01*
G01X-1005250Y-455000D02*
Y-450000D01*
X-1006150Y-451000D01*
G01Y-455000D02*
X-1004350D01*
G01X-995200D02*
Y-450000D01*
X-993250Y-454167D01*
X-991300Y-450000D01*
Y-455000D01*
G01X-988150Y-450000D02*
X-986350D01*
G01X-987250D02*
Y-455000D01*
G01X-988150D02*
X-986350D01*
G01X-979600Y-450417D02*
X-980050Y-450167D01*
X-980575Y-450000D01*
X-981175D01*
X-981850Y-450250D01*
X-982375Y-450667D01*
X-982750Y-451167D01*
X-983050Y-452000D01*
X-983125Y-452750D01*
X-982975Y-453500D01*
X-982750Y-454000D01*
X-982300Y-454500D01*
X-981775Y-454833D01*
X-981250Y-455000D01*
X-980725D01*
X-980200Y-454833D01*
X-979750Y-454583D01*
X-979375Y-454250D01*
G01X-976750Y-455000D02*
Y-450000D01*
X-974875D01*
X-974275Y-450250D01*
X-973900Y-450583D01*
X-973750Y-451250D01*
X-973900Y-451917D01*
X-974350Y-452333D01*
X-974875Y-452583D01*
X-976750D01*
G01X-974875D02*
X-973750Y-455000D01*
G01X-969250D02*
X-969850Y-454917D01*
X-970375Y-454583D01*
X-970825Y-454083D01*
X-971125Y-453500D01*
X-971275Y-452833D01*
Y-452167D01*
X-971125Y-451500D01*
X-970825Y-450917D01*
X-970375Y-450417D01*
X-969850Y-450083D01*
X-969250Y-450000D01*
X-968650Y-450083D01*
X-968125Y-450417D01*
X-967675Y-450917D01*
X-967375Y-451500D01*
X-967225Y-452167D01*
Y-452833D01*
X-967375Y-453500D01*
X-967675Y-454083D01*
X-968125Y-454583D01*
X-968650Y-454917D01*
X-969250Y-455000D01*
G01X-964825Y-454333D02*
X-964225Y-454750D01*
X-963550Y-455000D01*
X-962950D01*
X-962350Y-454750D01*
X-961900Y-454333D01*
X-961675Y-453750D01*
X-961825Y-453167D01*
X-962200Y-452667D01*
X-962875Y-452333D01*
X-963775Y-452167D01*
X-964300Y-451833D01*
X-964525Y-451250D01*
X-964375Y-450667D01*
X-964000Y-450250D01*
X-963475Y-450000D01*
X-962950D01*
X-962425Y-450167D01*
X-961975Y-450583D01*
G01X-957250Y-455000D02*
X-957850Y-454917D01*
X-958375Y-454583D01*
X-958825Y-454083D01*
X-959125Y-453500D01*
X-959275Y-452833D01*
Y-452167D01*
X-959125Y-451500D01*
X-958825Y-450917D01*
X-958375Y-450417D01*
X-957850Y-450083D01*
X-957250Y-450000D01*
X-956650Y-450083D01*
X-956125Y-450417D01*
X-955675Y-450917D01*
X-955375Y-451500D01*
X-955225Y-452167D01*
Y-452833D01*
X-955375Y-453500D01*
X-955675Y-454083D01*
X-956125Y-454583D01*
X-956650Y-454917D01*
X-957250Y-455000D01*
G01X-952675D02*
Y-450000D01*
X-949825D01*
G01X-950875Y-452417D02*
X-952675D01*
G01X-945250Y-450000D02*
Y-455000D01*
G01X-946975Y-450000D02*
X-943525D01*
G01X-935500D02*
X-934450Y-455000D01*
X-933250Y-450000D01*
X-932050Y-455000D01*
X-931000Y-450000D01*
G01X-929125Y-455000D02*
X-927250Y-450000D01*
X-925375Y-455000D01*
G01X-926050Y-453250D02*
X-928450D01*
G01X-921250Y-455000D02*
Y-452750D01*
X-922750Y-450000D01*
G01X-919750D02*
X-921250Y-452750D01*
G01X-611614Y-81890D02*
X-613539Y-83815D01*
X-630977D01*
X-654054Y-60738D01*
X-705120D01*
X-734607Y-90225D01*
Y-157798D01*
X-735133Y-158323D01*
X-735851D01*
X-738032Y-156142D01*
G01X-611614Y-86890D02*
X-613539Y-84965D01*
X-631453D01*
X-654530Y-61888D01*
X-704644D01*
X-733457Y-90701D01*
Y-158274D01*
X-734656Y-159473D01*
X-735851D01*
X-738032Y-161654D01*
G01X-730157Y-151024D02*
X-727977Y-153205D01*
X-727477D01*
X-726857Y-152585D01*
Y-90447D01*
X-702119Y-65708D01*
X-656774D01*
X-628668Y-93815D01*
X-618539D01*
X-616614Y-91890D01*
G01X-730157Y-156535D02*
X-727977Y-154355D01*
X-727000D01*
X-725707Y-153062D01*
Y-90923D01*
X-701643Y-66858D01*
X-657250D01*
X-629144Y-94965D01*
X-618539D01*
X-616614Y-96890D01*
G01Y-111890D02*
X-618539Y-113815D01*
X-627299D01*
X-643550Y-97564D01*
Y-94031D01*
X-644223Y-93358D01*
X-644224D01*
X-661229Y-76353D01*
X-694194D01*
X-711109Y-93268D01*
Y-152585D01*
X-711729Y-153205D01*
X-712229D01*
X-714409Y-151024D01*
G01X-611614Y-101890D02*
X-613539Y-103815D01*
X-621824D01*
X-624768Y-100871D01*
X-625105Y-100534D01*
X-625442Y-100197D01*
X-630632D01*
X-659869Y-70960D01*
X-699306D01*
X-718930Y-90585D01*
Y-157736D01*
X-719517Y-158323D01*
X-720103D01*
X-722283Y-156142D01*
G01X-616614Y-116890D02*
X-618539Y-114965D01*
X-627775D01*
X-644700Y-98040D01*
Y-94508D01*
X-661705Y-77503D01*
X-693718D01*
X-709959Y-93745D01*
Y-153062D01*
X-711252Y-154355D01*
X-712229D01*
X-714409Y-156535D01*
G01X-611614Y-106890D02*
X-613539Y-104965D01*
X-622301D01*
X-625918Y-101347D01*
X-631108Y-101347D01*
X-660345Y-72110D01*
X-698829D01*
X-717780Y-91061D01*
Y-158212D01*
X-719041Y-159473D01*
X-720103D01*
X-722283Y-161654D01*
G01X-706535Y-156142D02*
X-704355Y-158323D01*
X-703527D01*
X-703111Y-157907D01*
Y-93054D01*
X-691052Y-80996D01*
X-664839D01*
X-650000Y-95835D01*
Y-101274D01*
X-644574Y-106700D01*
X-641600D01*
X-624485Y-123815D01*
X-613539D01*
X-611614Y-121890D01*
G01X-698661Y-151024D02*
X-696481Y-153205D01*
X-695981D01*
X-695237Y-152461D01*
Y-94278D01*
X-687864Y-86904D01*
X-666528D01*
X-655197Y-98235D01*
X-655196D01*
X-654523Y-98908D01*
Y-107177D01*
X-627885Y-133815D01*
X-618539D01*
X-616614Y-131890D01*
G01X-706535Y-161654D02*
X-704355Y-159473D01*
X-703051D01*
X-701961Y-158384D01*
Y-93531D01*
X-690576Y-82146D01*
X-665316D01*
X-651150Y-96311D01*
Y-101750D01*
X-645050Y-107850D01*
X-642076D01*
X-624962Y-124965D01*
X-613539D01*
X-611614Y-126890D01*
G01X-616614Y-136890D02*
X-618539Y-134965D01*
X-628362D01*
X-655673Y-107653D01*
Y-99385D01*
X-656009Y-99048D01*
X-656010D01*
X-667004Y-88054D01*
X-687387D01*
X-694087Y-94754D01*
Y-152938D01*
X-695504Y-154355D01*
X-696481D01*
X-698661Y-156535D01*
G01X-690787Y-156142D02*
X-688606Y-158323D01*
X-687686D01*
X-687363Y-158000D01*
Y-93719D01*
X-684652Y-91007D01*
X-669740D01*
X-660330Y-100417D01*
X-659657Y-101090D01*
Y-112688D01*
X-634144Y-138200D01*
X-634100D01*
X-628485Y-143815D01*
X-613539D01*
X-611614Y-141890D01*
G01X-682913Y-151024D02*
X-680732Y-153205D01*
X-679871D01*
X-679489Y-152823D01*
Y-98787D01*
X-677196Y-96494D01*
X-673037D01*
X-673037Y-96493D01*
X-672085D01*
X-667183Y-101395D01*
Y-114917D01*
X-628285Y-153815D01*
X-618539D01*
X-616614Y-151890D01*
G01X-611614Y-146890D02*
X-613539Y-144965D01*
X-628962D01*
X-634576Y-139350D01*
X-634621D01*
X-660807Y-113164D01*
Y-101566D01*
X-661143Y-101230D01*
X-670216Y-92157D01*
X-684175D01*
X-686213Y-94195D01*
Y-158477D01*
X-687209Y-159473D01*
X-688606D01*
X-690787Y-161654D01*
G01X-682913Y-156535D02*
X-680732Y-154355D01*
X-679395D01*
X-678339Y-153299D01*
Y-99264D01*
X-676719Y-97644D01*
X-673037D01*
X-673037Y-97643D01*
X-672561D01*
X-668333Y-101871D01*
Y-115393D01*
X-628762Y-154965D01*
X-618539D01*
X-616614Y-156890D01*
G01X-675039Y-156142D02*
X-672858Y-158323D01*
X-670794D01*
X-668766Y-160350D01*
Y-164656D01*
X-658923Y-174499D01*
X-628638D01*
X-617954Y-163815D01*
X-613539D01*
X-611614Y-161890D01*
G01X-675039Y-161654D02*
X-672858Y-159473D01*
X-671270D01*
X-669916Y-160827D01*
Y-165132D01*
X-659400Y-175649D01*
X-658447D01*
X-628162Y-175649D01*
X-617478Y-164965D01*
X-613539D01*
X-611614Y-166890D01*
G54D15*
X-1015157Y-95824D03*
Y-80864D03*
Y-65903D03*
Y-50942D03*
X-1006299Y-95824D03*
X-997441D03*
X-1006299Y-80864D03*
X-997441D03*
X-1006299Y-65903D03*
X-997441D03*
X-1006299Y-50942D03*
X-997441D03*
X-971850Y-95824D03*
X-962992D03*
X-971850Y-80864D03*
X-962992D03*
X-971850Y-65903D03*
X-962992D03*
X-971850Y-50942D03*
X-962992D03*
X-954134Y-95824D03*
Y-80864D03*
Y-65903D03*
Y-50942D03*
G54D25*
G01X-874510Y-499000D02*
Y-493000D01*
X-871290Y-499000D01*
Y-493000D01*
G01X-867200Y-499000D02*
X-867760Y-498900D01*
X-868250Y-498500D01*
X-868670Y-497900D01*
X-868950Y-497200D01*
X-869090Y-496400D01*
Y-495600D01*
X-868950Y-494800D01*
X-868670Y-494100D01*
X-868250Y-493500D01*
X-867760Y-493100D01*
X-867200Y-493000D01*
X-866640Y-493100D01*
X-866150Y-493500D01*
X-865730Y-494100D01*
X-865450Y-494800D01*
X-865310Y-495600D01*
Y-496400D01*
X-865450Y-497200D01*
X-865730Y-497900D01*
X-866150Y-498500D01*
X-866640Y-498900D01*
X-867200Y-499000D01*
G01X-861500Y-493000D02*
Y-499000D01*
G01X-863110Y-493000D02*
X-859890D01*
G01X-856640D02*
X-854960D01*
G01X-855800D02*
Y-499000D01*
G01X-856640D02*
X-854960D01*
G01X-848560Y-493500D02*
X-848980Y-493200D01*
X-849470Y-493000D01*
X-850030D01*
X-850660Y-493300D01*
X-851150Y-493800D01*
X-851500Y-494400D01*
X-851780Y-495400D01*
X-851850Y-496300D01*
X-851710Y-497200D01*
X-851500Y-497800D01*
X-851080Y-498400D01*
X-850590Y-498800D01*
X-850100Y-499000D01*
X-849610D01*
X-849120Y-498800D01*
X-848700Y-498500D01*
X-848350Y-498100D01*
G01X-843000Y-499000D02*
X-845800D01*
Y-493000D01*
X-843000D01*
G01X-844120Y-495900D02*
X-845800D01*
G01X-833000Y-499000D02*
X-833560Y-498900D01*
X-834050Y-498500D01*
X-834470Y-497900D01*
X-834750Y-497200D01*
X-834890Y-496400D01*
Y-495600D01*
X-834750Y-494800D01*
X-834470Y-494100D01*
X-834050Y-493500D01*
X-833560Y-493100D01*
X-833000Y-493000D01*
X-832440Y-493100D01*
X-831950Y-493500D01*
X-831530Y-494100D01*
X-831250Y-494800D01*
X-831110Y-495600D01*
Y-496400D01*
X-831250Y-497200D01*
X-831530Y-497900D01*
X-831950Y-498500D01*
X-832440Y-498900D01*
X-833000Y-499000D01*
G01X-828630D02*
Y-493000D01*
X-825970D01*
G01X-826950Y-495900D02*
X-828630D01*
G01X-817300Y-499000D02*
Y-493000D01*
X-815620D01*
X-815060Y-493300D01*
X-814640Y-494000D01*
X-814500Y-494800D01*
X-814640Y-495600D01*
X-814990Y-496200D01*
X-815620Y-496500D01*
X-817300D01*
G01X-811600Y-499000D02*
Y-493000D01*
X-809850D01*
X-809290Y-493300D01*
X-808940Y-493700D01*
X-808800Y-494500D01*
X-808940Y-495300D01*
X-809360Y-495800D01*
X-809850Y-496100D01*
X-811600D01*
G01X-809850D02*
X-808800Y-499000D01*
G01X-804500D02*
X-805060Y-498900D01*
X-805550Y-498500D01*
X-805970Y-497900D01*
X-806250Y-497200D01*
X-806390Y-496400D01*
Y-495600D01*
X-806250Y-494800D01*
X-805970Y-494100D01*
X-805550Y-493500D01*
X-805060Y-493100D01*
X-804500Y-493000D01*
X-803940Y-493100D01*
X-803450Y-493500D01*
X-803030Y-494100D01*
X-802750Y-494800D01*
X-802610Y-495600D01*
Y-496400D01*
X-802750Y-497200D01*
X-803030Y-497900D01*
X-803450Y-498500D01*
X-803940Y-498900D01*
X-804500Y-499000D01*
G01X-800200D02*
Y-493000D01*
X-798520D01*
X-797960Y-493300D01*
X-797540Y-494000D01*
X-797400Y-494800D01*
X-797540Y-495600D01*
X-797890Y-496200D01*
X-798520Y-496500D01*
X-800200D01*
G01X-794500Y-499000D02*
Y-493000D01*
X-792750D01*
X-792190Y-493300D01*
X-791840Y-493700D01*
X-791700Y-494500D01*
X-791840Y-495300D01*
X-792260Y-495800D01*
X-792750Y-496100D01*
X-794500D01*
G01X-792750D02*
X-791700Y-499000D01*
G01X-788240Y-493000D02*
X-786560D01*
G01X-787400D02*
Y-499000D01*
G01X-788240D02*
X-786560D01*
G01X-780300D02*
X-783100D01*
Y-493000D01*
X-780300D01*
G01X-781420Y-495900D02*
X-783100D01*
G01X-776000Y-493000D02*
Y-499000D01*
G01X-777610Y-493000D02*
X-774390D01*
G01X-772050Y-499000D02*
X-770300Y-493000D01*
X-768550Y-499000D01*
G01X-769180Y-496900D02*
X-771420D01*
G01X-766000Y-499000D02*
Y-493000D01*
X-764250D01*
X-763690Y-493300D01*
X-763340Y-493700D01*
X-763200Y-494500D01*
X-763340Y-495300D01*
X-763760Y-495800D01*
X-764250Y-496100D01*
X-766000D01*
G01X-764250D02*
X-763200Y-499000D01*
G01X-758900D02*
Y-496300D01*
X-760300Y-493000D01*
G01X-757500D02*
X-758900Y-496300D01*
G01X-748900Y-499000D02*
Y-493000D01*
X-747220D01*
X-746660Y-493300D01*
X-746240Y-494000D01*
X-746100Y-494800D01*
X-746240Y-495600D01*
X-746590Y-496200D01*
X-747220Y-496500D01*
X-748900D01*
G01X-743200Y-499000D02*
Y-493000D01*
X-741450D01*
X-740890Y-493300D01*
X-740540Y-493700D01*
X-740400Y-494500D01*
X-740540Y-495300D01*
X-740960Y-495800D01*
X-741450Y-496100D01*
X-743200D01*
G01X-741450D02*
X-740400Y-499000D01*
G01X-736100D02*
X-736660Y-498900D01*
X-737150Y-498500D01*
X-737570Y-497900D01*
X-737850Y-497200D01*
X-737990Y-496400D01*
Y-495600D01*
X-737850Y-494800D01*
X-737570Y-494100D01*
X-737150Y-493500D01*
X-736660Y-493100D01*
X-736100Y-493000D01*
X-735540Y-493100D01*
X-735050Y-493500D01*
X-734630Y-494100D01*
X-734350Y-494800D01*
X-734210Y-495600D01*
Y-496400D01*
X-734350Y-497200D01*
X-734630Y-497900D01*
X-735050Y-498500D01*
X-735540Y-498900D01*
X-736100Y-499000D01*
G01X-731800D02*
Y-493000D01*
X-730120D01*
X-729560Y-493300D01*
X-729140Y-494000D01*
X-729000Y-494800D01*
X-729140Y-495600D01*
X-729490Y-496200D01*
X-730120Y-496500D01*
X-731800D01*
G01X-723300Y-499000D02*
X-726100D01*
Y-493000D01*
X-723300D01*
G01X-724420Y-495900D02*
X-726100D01*
G01X-720400Y-499000D02*
Y-493000D01*
X-718650D01*
X-718090Y-493300D01*
X-717740Y-493700D01*
X-717600Y-494500D01*
X-717740Y-495300D01*
X-718160Y-495800D01*
X-718650Y-496100D01*
X-720400D01*
G01X-718650D02*
X-717600Y-499000D01*
G01X-713300Y-493000D02*
Y-499000D01*
G01X-714910Y-493000D02*
X-711690D01*
G01X-707600Y-499000D02*
Y-496300D01*
X-709000Y-493000D01*
G01X-706200D02*
X-707600Y-496300D01*
G01X-701900Y-499200D02*
X-702040Y-499100D01*
Y-498900D01*
X-701900Y-498800D01*
X-701760Y-498900D01*
Y-499100D01*
X-701900Y-499200D01*
G01Y-496500D02*
X-702040Y-496400D01*
Y-496200D01*
X-701900Y-496100D01*
X-701760Y-496200D01*
Y-496400D01*
X-701900Y-496500D01*
G54D16*
X-806854Y-99635D03*
X-785200D03*
G54D26*
G01X-1644488Y-27500D02*
X-1644288D01*
X-1640888Y-30900D01*
X-1635000D01*
X-1610870Y-55030D01*
X-1464170D01*
X-1453500Y-65700D01*
X-1451700D01*
G01X-1654488Y-27300D02*
X-1648458Y-33330D01*
X-1636270D01*
X-1612350Y-57250D01*
X-1465950D01*
X-1453600Y-69600D01*
X-1451800D01*
G01X-1649488Y-27400D02*
X-1644788Y-32100D01*
X-1635500D01*
X-1611460Y-56140D01*
X-1465060D01*
X-1453500Y-67700D01*
X-1448800D01*
G01X-1639488Y-27500D02*
X-1637388Y-29600D01*
X-1634700D01*
X-1610380Y-53920D01*
X-1462480D01*
X-1452600Y-63800D01*
X-1448800D01*
G01X-1451500Y-61800D02*
X-1460490Y-52810D01*
X-1609890D01*
X-1626600Y-36100D01*
Y-33800D01*
X-1632800Y-27600D01*
X-1634488D01*
G01X-1448700Y-59900D02*
X-1450800D01*
X-1459000Y-51700D01*
X-1609400D01*
X-1625300Y-35800D01*
Y-31888D01*
X-1629488Y-27700D01*
G01X-1452100Y-82200D02*
X-1456600D01*
X-1459400Y-79400D01*
X-1498200D01*
X-1513690Y-63910D01*
X-1605650D01*
X-1613340Y-71600D01*
X-1618400D01*
G01X-1618300Y-63100D02*
X-1612600D01*
X-1608970Y-59470D01*
X-1468130D01*
X-1453600Y-74000D01*
X-1452000D01*
G01X-1621600Y-61100D02*
X-1612800D01*
X-1610060Y-58360D01*
X-1466740D01*
X-1453300Y-71800D01*
X-1449100D01*
G01X-1448900Y-76100D02*
X-1455300D01*
X-1458300Y-73100D01*
Y-70900D01*
X-1468620Y-60580D01*
X-1608080D01*
X-1612600Y-65100D01*
X-1621600D01*
G01X-1452000Y-78200D02*
X-1455500D01*
X-1459600Y-74100D01*
Y-71300D01*
X-1461200Y-69700D01*
X-1485200D01*
X-1493210Y-61690D01*
X-1607290D01*
X-1612800Y-67200D01*
X-1618500D01*
G01X-1449000Y-80300D02*
X-1455300D01*
X-1461300Y-74300D01*
X-1498900D01*
X-1510400Y-62800D01*
X-1606510D01*
X-1613110Y-69400D01*
X-1621600D01*
G01X-1298700Y-35700D02*
X-1301400Y-38400D01*
X-1311600D01*
X-1315500Y-42300D01*
Y-81000D01*
X-1299500Y-97000D01*
X-1291000D01*
X-1287260Y-100740D01*
Y-176140D01*
X-1285510Y-177890D01*
X-1280320D01*
X-1280180Y-178030D01*
X-1276860D01*
G01X-1279429Y-180579D02*
X-1284821D01*
X-1288400Y-177000D01*
Y-101600D01*
X-1291500Y-98500D01*
X-1300000D01*
X-1319600Y-78900D01*
Y-62100D01*
X-1317700Y-60200D01*
G01X-1295400Y-13400D02*
X-1301000D01*
X-1321500Y-33900D01*
Y-79500D01*
X-1306850Y-94150D01*
Y-95000D01*
G01X-1321000Y-94850D02*
X-1319500Y-93350D01*
Y-84500D01*
X-1323100Y-80900D01*
Y-31200D01*
X-1318500Y-26600D01*
Y-6000D01*
G01X-1248860Y-150200D02*
X-1249740D01*
X-1253390Y-146550D01*
Y-123370D01*
X-1275540Y-101220D01*
X-1283680D01*
X-1290100Y-94800D01*
X-1298200D01*
X-1308600Y-84400D01*
Y-81900D01*
X-1313400Y-77100D01*
Y-71541D01*
X-1310559Y-68700D01*
G01X-1311200Y-30200D02*
X-1313500D01*
X-1317700Y-34400D01*
Y-60200D01*
G01X-1298000Y-41200D02*
X-1305000Y-48200D01*
Y-63500D01*
X-1310200Y-68700D01*
X-1310559D01*
G01X-1298780Y-52200D02*
X-1273100Y-77880D01*
Y-91430D01*
X-1241400Y-123130D01*
Y-135300D01*
X-1236310Y-140390D01*
G01X-1249016Y-144800D02*
X-1247620Y-143404D01*
Y-120510D01*
X-1274800Y-93330D01*
Y-81600D01*
X-1297995Y-58405D01*
G01X-1250660Y-140480D02*
Y-121920D01*
X-1276400Y-96180D01*
Y-85200D01*
X-1298400Y-63200D01*
G01X-1181260Y-151417D02*
X-1185900Y-156057D01*
Y-181800D01*
X-1187160Y-183060D01*
X-1199580D01*
X-1205000Y-177640D01*
Y-175910D01*
X-1200220Y-171130D01*
Y-152400D01*
X-1205120Y-147500D01*
X-1213720D01*
X-1217780Y-143440D01*
X-1245450D01*
X-1246810Y-144800D01*
X-1249016D01*
G01X-1181260Y-156929D02*
X-1184550Y-160219D01*
Y-182850D01*
X-1185930Y-184230D01*
X-1200540D01*
X-1206120Y-178650D01*
Y-175380D01*
X-1201480Y-170740D01*
Y-153200D01*
X-1205890Y-148790D01*
X-1214310D01*
X-1217860Y-145240D01*
X-1244910D01*
X-1247340Y-147670D01*
X-1249750D01*
X-1251500Y-145920D01*
Y-141320D01*
X-1250660Y-140480D01*
G01X-1202580Y-176300D02*
X-1201430Y-177450D01*
Y-179310D01*
X-1198810Y-181930D01*
X-1195070D01*
X-1193880Y-180740D01*
Y-126640D01*
X-1197915Y-122605D01*
X-1204895D01*
X-1213300Y-114200D01*
Y-74100D01*
X-1212100Y-72900D01*
Y-72700D01*
X-1206200Y-66800D01*
Y-47900D01*
X-1195400Y-37100D01*
X-1190200D01*
X-1188000Y-39300D01*
Y-43600D01*
X-1190900Y-46500D01*
X-1191000D01*
G01X-1189134Y-145512D02*
X-1189188D01*
X-1192000Y-142700D01*
Y-125000D01*
X-1202100Y-114900D01*
Y-103200D01*
G01X-1189134Y-134488D02*
Y-123566D01*
X-1199000Y-113700D01*
Y-102100D01*
X-1202800Y-98300D01*
Y-50100D01*
X-1193200Y-40500D01*
X-1191200D01*
G01X-1178900Y-46700D02*
X-1180900Y-48700D01*
X-1187900D01*
X-1199800Y-60600D01*
Y-96300D01*
X-1193500Y-102600D01*
Y-114700D01*
X-1186200Y-122000D01*
Y-136700D01*
X-1189134Y-139634D01*
Y-140000D01*
G01X-1178800Y-34800D02*
X-1177040Y-36560D01*
Y-48240D01*
X-1179100Y-50300D01*
X-1185800D01*
X-1196400Y-60900D01*
Y-93400D01*
X-1188500Y-101300D01*
Y-114500D01*
X-1178400Y-124600D01*
Y-130600D01*
X-1181260Y-133460D01*
Y-134882D01*
G01X-1192359Y-5800D02*
X-1187000Y-11159D01*
Y-19000D01*
X-1169750Y-36250D01*
Y-39150D01*
X-1172000Y-41400D01*
X-1173200D01*
X-1174560Y-42760D01*
Y-45340D01*
X-1173380Y-46520D01*
X-1167880D01*
X-1156400Y-58000D01*
Y-96300D01*
X-1161900Y-101800D01*
Y-112900D01*
X-1168600Y-119600D01*
Y-131794D01*
X-1165512Y-134882D01*
G01X-1112402Y-101600D02*
X-1111200Y-102802D01*
Y-107100D01*
X-1113600Y-109500D01*
X-1128200D01*
X-1149800Y-131100D01*
Y-178400D01*
X-1153800Y-182400D01*
X-1167100D01*
X-1169500Y-180000D01*
Y-160100D01*
X-1173065Y-156535D01*
X-1173386D01*
G01X-1173847Y-162047D02*
X-1177400Y-165600D01*
Y-180900D01*
X-1174200Y-184100D01*
X-1151598D01*
X-1147300Y-179802D01*
Y-132000D01*
X-1127000Y-111700D01*
X-1112400D01*
X-1109300Y-108600D01*
Y-104200D01*
G01X-1173847Y-162047D02*
X-1173953D01*
X-1177300Y-158700D01*
Y-133800D01*
X-1175500Y-132000D01*
Y-122700D01*
X-1179100Y-119100D01*
Y-113100D01*
X-1160700Y-94700D01*
Y-60200D01*
X-1171200Y-49700D01*
X-1173200D01*
G01X-1173847Y-162047D02*
X-1173386D01*
G01Y-151024D02*
Y-150986D01*
X-1170000Y-147600D01*
Y-133800D01*
X-1172100Y-131700D01*
Y-119800D01*
X-1166700Y-114400D01*
Y-103650D01*
X-1158200Y-95150D01*
Y-59100D01*
X-1169600Y-47700D01*
X-1174330D01*
X-1175840Y-46190D01*
Y-41840D01*
X-1172500Y-38500D01*
G01Y-44000D02*
X-1166700D01*
X-1148900Y-61800D01*
Y-77900D01*
X-1131700Y-95100D01*
Y-105800D01*
X-1130600Y-106900D01*
X-1114700D01*
X-1113300Y-105500D01*
Y-102498D01*
X-1112402Y-101600D01*
G01X-1125000Y-101700D02*
Y-96900D01*
X-1146900Y-75000D01*
Y-59900D01*
X-1164900Y-41900D01*
Y-37300D01*
X-1178950Y-23250D01*
G01X-1121870Y-104330D02*
X-1122900Y-103300D01*
Y-70600D01*
X-1158000Y-35500D01*
X-1160500D01*
X-1177800Y-18200D01*
Y-12100D01*
G01X-1178800Y-5800D02*
X-1174800Y-9800D01*
Y-16600D01*
X-1172400Y-19000D01*
X-1168300D01*
X-1163300Y-24000D01*
Y-26700D01*
X-1120600Y-69400D01*
Y-102500D01*
X-1118810Y-104290D01*
X-1115540D01*
X-1115490Y-104240D01*
G01X-1154200Y-103100D02*
X-1151600Y-105700D01*
Y-111100D01*
X-1154900Y-114400D01*
Y-120600D01*
X-1161500Y-127200D01*
Y-147600D01*
X-1165317Y-151417D01*
X-1165512D01*
G01X-1160150Y-26750D02*
X-1118701Y-68200D01*
Y-101759D01*
G01X-1158700Y-16250D02*
Y-24800D01*
X-1151000Y-32500D01*
Y-32600D01*
X-1115700Y-67900D01*
Y-92300D01*
X-1106102Y-101898D01*
Y-102100D01*
G01X-1159700Y-5750D02*
X-1156000Y-9450D01*
Y-24500D01*
X-1113700Y-66800D01*
Y-91400D01*
X-1102953Y-102147D01*
Y-104200D01*
G01X-452700Y-69000D02*
X-447300Y-74400D01*
Y-81300D01*
X-443149Y-85451D01*
Y-89151D01*
X-433800Y-98500D01*
X-421421D01*
X-418021Y-101900D01*
X-410900D01*
X-406000Y-106800D01*
Y-132000D01*
X-417400Y-143400D01*
Y-175200D01*
X-410000Y-182600D01*
X-406020D01*
X-405540Y-183080D01*
G01Y-179630D02*
Y-179271D01*
X-407200Y-177611D01*
Y-149660D01*
X-403000Y-145460D01*
Y-105000D01*
X-407900Y-100100D01*
X-414800D01*
X-417900Y-97000D01*
X-428100D01*
X-441400Y-83700D01*
Y-79800D01*
X-444900Y-76300D01*
Y-57000D01*
X-442900Y-55000D01*
X-435000D01*
X-432100Y-52100D01*
X-430180D01*
G01X-442800Y-46600D02*
X-448200D01*
X-451900Y-50300D01*
Y-68200D01*
X-452700Y-69000D01*
G01X-380421Y-147000D02*
Y-142950D01*
X-383991Y-139380D01*
X-391490D01*
X-400100Y-130770D01*
Y-114721D01*
X-400300Y-114521D01*
Y-95300D01*
X-406250Y-89350D01*
X-432750D01*
X-436900Y-85200D01*
Y-73659D01*
X-441959Y-68600D01*
G01X-432118Y-87082D02*
X-433100Y-86100D01*
Y-59000D01*
X-429810Y-55710D01*
X-429040D01*
X-425600Y-52270D01*
Y-41600D01*
X-429400Y-37800D01*
X-431900D01*
X-433100Y-36600D01*
Y-22900D01*
X-424600Y-14400D01*
G01X-429400Y-41100D02*
X-427400Y-43100D01*
Y-52500D01*
X-429420Y-54520D01*
X-431120D01*
X-437300Y-60700D01*
Y-63800D01*
X-441959Y-68459D01*
Y-68600D01*
G01X-429000Y-57600D02*
X-428721D01*
X-391760Y-94561D01*
Y-121480D01*
X-389600Y-123640D01*
G01X-430700Y-63100D02*
X-428421D01*
X-396221Y-95300D01*
Y-120769D01*
X-389770Y-127220D01*
G01X-373620Y-124430D02*
X-377791D01*
X-387452Y-114770D01*
Y-93450D01*
X-420401Y-60501D01*
Y-42699D01*
X-427500Y-35600D01*
X-430400D01*
G01X-389770Y-127220D02*
X-380735Y-136255D01*
X-377035D01*
X-372890Y-140400D01*
X-351400D01*
X-343750Y-148050D01*
Y-175350D01*
X-335200Y-183900D01*
X-310000D01*
X-307100Y-181000D01*
Y-161010D01*
X-311181Y-156929D01*
G01Y-151417D02*
X-315100Y-155336D01*
Y-180700D01*
X-316900Y-182500D01*
X-333500D01*
X-335730Y-180270D01*
Y-174410D01*
X-331580Y-170260D01*
Y-143820D01*
X-338900Y-136500D01*
X-348600D01*
X-351310Y-139210D01*
X-367990D01*
X-379080Y-128120D01*
X-385120D01*
X-389600Y-123640D01*
G01X-321500Y-47500D02*
X-318100Y-44100D01*
Y-41100D01*
X-319400Y-39800D01*
X-326300D01*
X-344700Y-58200D01*
Y-116200D01*
X-329800Y-131100D01*
Y-171300D01*
X-333450Y-174950D01*
G01X-319055Y-134488D02*
Y-129445D01*
X-332300Y-116200D01*
Y-52600D01*
X-321700Y-42000D01*
G01X-309400Y-47700D02*
X-315800D01*
X-329100Y-61000D01*
Y-111300D01*
X-315300Y-125100D01*
Y-136245D01*
X-319055Y-140000D01*
G01X-308500Y-36400D02*
Y-45300D01*
X-307200Y-46600D01*
Y-48800D01*
X-310300Y-51900D01*
X-313900D01*
X-326200Y-64200D01*
Y-95500D01*
X-308200Y-113500D01*
Y-131901D01*
X-311181Y-134882D01*
G01X-295433D02*
X-298600Y-131715D01*
Y-127600D01*
X-290200Y-119200D01*
Y-100700D01*
X-284200Y-94700D01*
Y-61400D01*
X-300200Y-45400D01*
X-304300D01*
X-305300Y-44400D01*
Y-23700D01*
X-315000Y-14000D01*
X-315100D01*
X-321800Y-7300D01*
G01X-309400Y-25100D02*
X-306430Y-28070D01*
Y-45670D01*
X-305400Y-46700D01*
X-301300D01*
X-286300Y-61700D01*
Y-93600D01*
X-293300Y-100600D01*
Y-116600D01*
X-300200Y-123500D01*
Y-147879D01*
X-303307Y-150986D01*
Y-151024D01*
G01Y-140000D02*
X-306200Y-137107D01*
Y-125400D01*
X-296400Y-115600D01*
Y-113500D01*
G01X-303200Y-43300D02*
X-299550D01*
X-282600Y-60250D01*
Y-75900D01*
X-259600Y-98900D01*
Y-100300D01*
X-251500Y-108400D01*
X-243500D01*
X-242323Y-107223D01*
Y-101600D01*
G01X-308800Y-7400D02*
X-308500Y-7700D01*
X-303900D01*
X-293900Y-17700D01*
Y-27000D01*
X-291499Y-29401D01*
X-287799D01*
X-251400Y-65800D01*
Y-90950D01*
X-251350Y-91000D01*
X-251300D01*
X-245411Y-96888D01*
Y-104240D01*
G01X-302500Y-15200D02*
X-298500Y-19200D01*
Y-31800D01*
X-279800Y-50500D01*
Y-76521D01*
X-254921Y-101400D01*
Y-101700D01*
G01X-251792Y-104330D02*
Y-101530D01*
X-278500Y-74821D01*
Y-49200D01*
X-296300Y-31400D01*
Y-17600D01*
X-301900Y-12000D01*
X-306272D01*
X-307900Y-13628D01*
G01X-295433Y-151417D02*
X-290800Y-146784D01*
Y-133600D01*
X-282300Y-125100D01*
Y-113700D01*
G01X-295433Y-140394D02*
X-292400Y-137361D01*
Y-130700D01*
X-286500Y-124800D01*
Y-113700D01*
G01X-289500Y-32500D02*
X-252921Y-69079D01*
Y-92800D01*
X-248622Y-97099D01*
Y-101759D01*
G01X-236024Y-102100D02*
Y-101898D01*
X-249400Y-88521D01*
Y-62900D01*
X-286300Y-26000D01*
X-290800D01*
G01X-290300Y-4400D02*
X-283321Y-11379D01*
Y-24679D01*
X-246900Y-61100D01*
Y-88121D01*
X-232874Y-102147D01*
Y-104200D01*
G01X-278100Y-178200D02*
Y-129600D01*
X-264900Y-116400D01*
X-245022D01*
X-239222Y-110600D01*
Y-104200D01*
G54D17*
X-486810Y-145000D03*
G54D27*
G01X-1189333Y-572500D02*
Y-565500D01*
X-1187667D01*
X-1187000Y-565850D01*
X-1186500Y-566317D01*
X-1186083Y-567017D01*
X-1185750Y-567833D01*
X-1185667Y-569000D01*
X-1185750Y-570167D01*
X-1186083Y-570983D01*
X-1186500Y-571684D01*
X-1187000Y-572150D01*
X-1187667Y-572500D01*
X-1189333D01*
G01X-1180700D02*
X-1181367Y-572383D01*
X-1181950Y-571917D01*
X-1182450Y-571217D01*
X-1182783Y-570400D01*
X-1182950Y-569467D01*
Y-568533D01*
X-1182783Y-567600D01*
X-1182450Y-566783D01*
X-1181950Y-566083D01*
X-1181367Y-565617D01*
X-1180700Y-565500D01*
X-1180033Y-565617D01*
X-1179450Y-566083D01*
X-1178950Y-566783D01*
X-1178617Y-567600D01*
X-1178450Y-568533D01*
Y-569467D01*
X-1178617Y-570400D01*
X-1178950Y-571217D01*
X-1179450Y-571917D01*
X-1180033Y-572383D01*
X-1180700Y-572500D01*
G01X-1172067Y-566083D02*
X-1172567Y-565733D01*
X-1173150Y-565500D01*
X-1173817D01*
X-1174567Y-565850D01*
X-1175150Y-566433D01*
X-1175567Y-567133D01*
X-1175900Y-568300D01*
X-1175983Y-569350D01*
X-1175817Y-570400D01*
X-1175567Y-571100D01*
X-1175067Y-571800D01*
X-1174483Y-572267D01*
X-1173900Y-572500D01*
X-1173317D01*
X-1172733Y-572267D01*
X-1172233Y-571917D01*
X-1171817Y-571450D01*
G01X-1168933Y-565500D02*
Y-570517D01*
X-1168600Y-571567D01*
X-1167933Y-572267D01*
X-1167100Y-572500D01*
X-1166267Y-572267D01*
X-1165600Y-571567D01*
X-1165267Y-570517D01*
Y-565500D01*
G01X-1162467Y-572500D02*
Y-565500D01*
X-1160300Y-571333D01*
X-1158133Y-565500D01*
Y-572500D01*
G01X-1151833D02*
X-1155167D01*
Y-565500D01*
X-1151833D01*
G01X-1153167Y-568883D02*
X-1155167D01*
G01X-1148617Y-572500D02*
Y-565500D01*
X-1144783Y-572500D01*
Y-565500D01*
G01X-1139900D02*
Y-572500D01*
G01X-1141817Y-565500D02*
X-1137983D01*
G01X-1128217Y-572500D02*
Y-565500D01*
X-1124383Y-572500D01*
Y-565500D01*
G01X-1121333D02*
Y-570517D01*
X-1121000Y-571567D01*
X-1120333Y-572267D01*
X-1119500Y-572500D01*
X-1118667Y-572267D01*
X-1118000Y-571567D01*
X-1117667Y-570517D01*
Y-565500D01*
G01X-1114867Y-572500D02*
Y-565500D01*
X-1112700Y-571333D01*
X-1110533Y-565500D01*
Y-572500D01*
G01X-1105233Y-568767D02*
X-1104900Y-568417D01*
X-1104650Y-567833D01*
X-1104483Y-567017D01*
X-1104650Y-566317D01*
X-1104983Y-565850D01*
X-1105567Y-565500D01*
X-1107817D01*
Y-572500D01*
X-1105067D01*
X-1104483Y-572033D01*
X-1104150Y-571333D01*
X-1103983Y-570517D01*
X-1104150Y-569700D01*
X-1104650Y-569000D01*
X-1105233Y-568767D01*
X-1107817D01*
G01X-1097433Y-572500D02*
X-1100767D01*
Y-565500D01*
X-1097433D01*
G01X-1098767Y-568883D02*
X-1100767D01*
G01X-1093967Y-572500D02*
Y-565500D01*
X-1091883D01*
X-1091217Y-565850D01*
X-1090800Y-566317D01*
X-1090633Y-567250D01*
X-1090800Y-568183D01*
X-1091300Y-568767D01*
X-1091883Y-569117D01*
X-1093967D01*
G01X-1091883D02*
X-1090633Y-572500D01*
G01X-1189250Y-531567D02*
X-1188583Y-532150D01*
X-1187833Y-532500D01*
X-1187167D01*
X-1186500Y-532150D01*
X-1186000Y-531567D01*
X-1185750Y-530750D01*
X-1185917Y-529933D01*
X-1186333Y-529233D01*
X-1187083Y-528767D01*
X-1188083Y-528533D01*
X-1188667Y-528067D01*
X-1188917Y-527250D01*
X-1188750Y-526433D01*
X-1188333Y-525850D01*
X-1187750Y-525500D01*
X-1187167D01*
X-1186583Y-525733D01*
X-1186083Y-526317D01*
G01X-1182450Y-532500D02*
Y-525500D01*
G01X-1178950D02*
Y-532500D01*
G01Y-529000D02*
X-1182450D01*
G01X-1172233Y-532500D02*
X-1175567D01*
Y-525500D01*
X-1172233D01*
G01X-1173567Y-528883D02*
X-1175567D01*
G01X-1165433Y-532500D02*
X-1168767D01*
Y-525500D01*
X-1165433D01*
G01X-1166767Y-528883D02*
X-1168767D01*
G01X-1160300Y-525500D02*
Y-532500D01*
G01X-1162217Y-525500D02*
X-1158383D01*
G01X-1146700D02*
Y-532500D01*
G01X-1148617Y-525500D02*
X-1144783D01*
G01X-1140900D02*
X-1138900D01*
G01X-1139900D02*
Y-532500D01*
G01X-1140900D02*
X-1138900D01*
G01X-1133100Y-525500D02*
Y-532500D01*
G01X-1135017Y-525500D02*
X-1131183D01*
G01X-1127967D02*
Y-532500D01*
X-1124633D01*
G01X-1117833D02*
X-1121167D01*
Y-525500D01*
X-1117833D01*
G01X-1119167Y-528883D02*
X-1121167D01*
G01X-1112700Y-532733D02*
X-1112867Y-532617D01*
Y-532383D01*
X-1112700Y-532267D01*
X-1112533Y-532383D01*
Y-532617D01*
X-1112700Y-532733D01*
G01Y-529584D02*
X-1112867Y-529467D01*
Y-529233D01*
X-1112700Y-529117D01*
X-1112533Y-529233D01*
Y-529467D01*
X-1112700Y-529584D01*
G01X-1187500Y-485500D02*
Y-492500D01*
G01X-1189417Y-485500D02*
X-1185583D01*
G01X-1181700D02*
X-1179700D01*
G01X-1180700D02*
Y-492500D01*
G01X-1181700D02*
X-1179700D01*
G01X-1173900Y-485500D02*
Y-492500D01*
G01X-1175817Y-485500D02*
X-1171983D01*
G01X-1168767D02*
Y-492500D01*
X-1165433D01*
G01X-1158633D02*
X-1161967D01*
Y-485500D01*
X-1158633D01*
G01X-1159967Y-488883D02*
X-1161967D01*
G01X-916667Y-570000D02*
Y-563000D01*
X-914583D01*
X-913917Y-563350D01*
X-913500Y-563817D01*
X-913333Y-564750D01*
X-913500Y-565683D01*
X-914000Y-566267D01*
X-914583Y-566617D01*
X-916667D01*
G01X-914583D02*
X-913333Y-570000D01*
G01X-906533D02*
X-909867D01*
Y-563000D01*
X-906533D01*
G01X-907867Y-566383D02*
X-909867D01*
G01X-903483Y-563000D02*
X-901400Y-570000D01*
X-899317Y-563000D01*
G01X-907850Y-451567D02*
X-907183Y-452150D01*
X-906433Y-452500D01*
X-905767D01*
X-905100Y-452150D01*
X-904600Y-451567D01*
X-904350Y-450750D01*
X-904517Y-449933D01*
X-904933Y-449233D01*
X-905683Y-448767D01*
X-906683Y-448533D01*
X-907267Y-448067D01*
X-907517Y-447250D01*
X-907350Y-446433D01*
X-906933Y-445850D01*
X-906350Y-445500D01*
X-905767D01*
X-905183Y-445733D01*
X-904683Y-446317D01*
G01X-897467Y-446083D02*
X-897967Y-445733D01*
X-898550Y-445500D01*
X-899217D01*
X-899967Y-445850D01*
X-900550Y-446433D01*
X-900967Y-447133D01*
X-901300Y-448300D01*
X-901383Y-449350D01*
X-901217Y-450400D01*
X-900967Y-451100D01*
X-900467Y-451800D01*
X-899883Y-452267D01*
X-899300Y-452500D01*
X-898717D01*
X-898133Y-452267D01*
X-897633Y-451917D01*
X-897217Y-451450D01*
G01X-894583Y-452500D02*
X-892500Y-445500D01*
X-890417Y-452500D01*
G01X-891167Y-450050D02*
X-893833D01*
G01X-887367Y-445500D02*
Y-452500D01*
X-884033D01*
G01X-877233D02*
X-880567D01*
Y-445500D01*
X-877233D01*
G01X-878567Y-448883D02*
X-880567D01*
G01X-874333Y-572500D02*
Y-565500D01*
X-872667D01*
X-872000Y-565850D01*
X-871500Y-566317D01*
X-871083Y-567017D01*
X-870750Y-567833D01*
X-870667Y-569000D01*
X-870750Y-570167D01*
X-871083Y-570983D01*
X-871500Y-571684D01*
X-872000Y-572150D01*
X-872667Y-572500D01*
X-874333D01*
G01X-866700Y-565500D02*
X-864700D01*
G01X-865700D02*
Y-572500D01*
G01X-866700D02*
X-864700D01*
G01X-860650Y-571567D02*
X-859983Y-572150D01*
X-859233Y-572500D01*
X-858567D01*
X-857900Y-572150D01*
X-857400Y-571567D01*
X-857150Y-570750D01*
X-857317Y-569933D01*
X-857733Y-569233D01*
X-858483Y-568767D01*
X-859483Y-568533D01*
X-860067Y-568067D01*
X-860317Y-567250D01*
X-860150Y-566433D01*
X-859733Y-565850D01*
X-859150Y-565500D01*
X-858567D01*
X-857983Y-565733D01*
X-857483Y-566317D01*
G01X-850267Y-566083D02*
X-850767Y-565733D01*
X-851350Y-565500D01*
X-852017D01*
X-852767Y-565850D01*
X-853350Y-566433D01*
X-853767Y-567133D01*
X-854100Y-568300D01*
X-854183Y-569350D01*
X-854017Y-570400D01*
X-853767Y-571100D01*
X-853267Y-571800D01*
X-852683Y-572267D01*
X-852100Y-572500D01*
X-851517D01*
X-850933Y-572267D01*
X-850433Y-571917D01*
X-850017Y-571450D01*
G01X-846967Y-565500D02*
Y-572500D01*
X-843633D01*
G01X-838500D02*
X-839167Y-572383D01*
X-839750Y-571917D01*
X-840250Y-571217D01*
X-840583Y-570400D01*
X-840750Y-569467D01*
Y-568533D01*
X-840583Y-567600D01*
X-840250Y-566783D01*
X-839750Y-566083D01*
X-839167Y-565617D01*
X-838500Y-565500D01*
X-837833Y-565617D01*
X-837250Y-566083D01*
X-836750Y-566783D01*
X-836417Y-567600D01*
X-836250Y-568533D01*
Y-569467D01*
X-836417Y-570400D01*
X-836750Y-571217D01*
X-837250Y-571917D01*
X-837833Y-572383D01*
X-838500Y-572500D01*
G01X-833450Y-571567D02*
X-832783Y-572150D01*
X-832033Y-572500D01*
X-831367D01*
X-830700Y-572150D01*
X-830200Y-571567D01*
X-829950Y-570750D01*
X-830117Y-569933D01*
X-830533Y-569233D01*
X-831283Y-568767D01*
X-832283Y-568533D01*
X-832867Y-568067D01*
X-833117Y-567250D01*
X-832950Y-566433D01*
X-832533Y-565850D01*
X-831950Y-565500D01*
X-831367D01*
X-830783Y-565733D01*
X-830283Y-566317D01*
G01X-823233Y-572500D02*
X-826567D01*
Y-565500D01*
X-823233D01*
G01X-824567Y-568883D02*
X-826567D01*
G01X-819933Y-572500D02*
Y-565500D01*
X-818267D01*
X-817600Y-565850D01*
X-817100Y-566317D01*
X-816683Y-567017D01*
X-816350Y-567833D01*
X-816267Y-569000D01*
X-816350Y-570167D01*
X-816683Y-570983D01*
X-817100Y-571684D01*
X-817600Y-572150D01*
X-818267Y-572500D01*
X-819933D01*
G01X-807000Y-565500D02*
X-805833Y-572500D01*
X-804500Y-565500D01*
X-803167Y-572500D01*
X-802000Y-565500D01*
G01X-798700D02*
X-796700D01*
G01X-797700D02*
Y-572500D01*
G01X-798700D02*
X-796700D01*
G01X-790900Y-565500D02*
Y-572500D01*
G01X-792817Y-565500D02*
X-788983D01*
G01X-785850Y-572500D02*
Y-565500D01*
G01X-782350D02*
Y-572500D01*
G01Y-569000D02*
X-785850D01*
G01X-777300Y-572500D02*
X-777967Y-572383D01*
X-778550Y-571917D01*
X-779050Y-571217D01*
X-779383Y-570400D01*
X-779550Y-569467D01*
Y-568533D01*
X-779383Y-567600D01*
X-779050Y-566783D01*
X-778550Y-566083D01*
X-777967Y-565617D01*
X-777300Y-565500D01*
X-776633Y-565617D01*
X-776050Y-566083D01*
X-775550Y-566783D01*
X-775217Y-567600D01*
X-775050Y-568533D01*
Y-569467D01*
X-775217Y-570400D01*
X-775550Y-571217D01*
X-776050Y-571917D01*
X-776633Y-572383D01*
X-777300Y-572500D01*
G01X-772333Y-565500D02*
Y-570517D01*
X-772000Y-571567D01*
X-771333Y-572267D01*
X-770500Y-572500D01*
X-769667Y-572267D01*
X-769000Y-571567D01*
X-768667Y-570517D01*
Y-565500D01*
G01X-763700D02*
Y-572500D01*
G01X-765617Y-565500D02*
X-761783D01*
G01X-750100D02*
Y-572500D01*
G01X-752017Y-565500D02*
X-748183D01*
G01X-745050Y-572500D02*
Y-565500D01*
G01X-741550D02*
Y-572500D01*
G01Y-569000D02*
X-745050D01*
G01X-734833Y-572500D02*
X-738167D01*
Y-565500D01*
X-734833D01*
G01X-736167Y-568883D02*
X-738167D01*
G01X-724567Y-572500D02*
Y-565500D01*
X-722567D01*
X-721900Y-565850D01*
X-721400Y-566667D01*
X-721233Y-567600D01*
X-721400Y-568533D01*
X-721817Y-569233D01*
X-722567Y-569584D01*
X-724567D01*
G01X-717767Y-572500D02*
Y-565500D01*
X-715683D01*
X-715017Y-565850D01*
X-714600Y-566317D01*
X-714433Y-567250D01*
X-714600Y-568183D01*
X-715100Y-568767D01*
X-715683Y-569117D01*
X-717767D01*
G01X-715683D02*
X-714433Y-572500D01*
G01X-710300Y-565500D02*
X-708300D01*
G01X-709300D02*
Y-572500D01*
G01X-710300D02*
X-708300D01*
G01X-702500D02*
X-703167Y-572383D01*
X-703750Y-571917D01*
X-704250Y-571217D01*
X-704583Y-570400D01*
X-704750Y-569467D01*
Y-568533D01*
X-704583Y-567600D01*
X-704250Y-566783D01*
X-703750Y-566083D01*
X-703167Y-565617D01*
X-702500Y-565500D01*
X-701833Y-565617D01*
X-701250Y-566083D01*
X-700750Y-566783D01*
X-700417Y-567600D01*
X-700250Y-568533D01*
Y-569467D01*
X-700417Y-570400D01*
X-700750Y-571217D01*
X-701250Y-571917D01*
X-701833Y-572383D01*
X-702500Y-572500D01*
G01X-697367D02*
Y-565500D01*
X-695283D01*
X-694617Y-565850D01*
X-694200Y-566317D01*
X-694033Y-567250D01*
X-694200Y-568183D01*
X-694700Y-568767D01*
X-695283Y-569117D01*
X-697367D01*
G01X-695283D02*
X-694033Y-572500D01*
G01X-684600Y-565500D02*
X-683433Y-572500D01*
X-682100Y-565500D01*
X-680767Y-572500D01*
X-679600Y-565500D01*
G01X-676967Y-572500D02*
Y-565500D01*
X-674883D01*
X-674217Y-565850D01*
X-673800Y-566317D01*
X-673633Y-567250D01*
X-673800Y-568183D01*
X-674300Y-568767D01*
X-674883Y-569117D01*
X-676967D01*
G01X-674883D02*
X-673633Y-572500D01*
G01X-669500Y-565500D02*
X-667500D01*
G01X-668500D02*
Y-572500D01*
G01X-669500D02*
X-667500D01*
G01X-661700Y-565500D02*
Y-572500D01*
G01X-663617Y-565500D02*
X-659783D01*
G01X-654900D02*
Y-572500D01*
G01X-656817Y-565500D02*
X-652983D01*
G01X-646433Y-572500D02*
X-649767D01*
Y-565500D01*
X-646433D01*
G01X-647767Y-568883D02*
X-649767D01*
G01X-643217Y-572500D02*
Y-565500D01*
X-639383Y-572500D01*
Y-565500D01*
G01X-625867Y-566083D02*
X-626367Y-565733D01*
X-626950Y-565500D01*
X-627617D01*
X-628367Y-565850D01*
X-628950Y-566433D01*
X-629367Y-567133D01*
X-629700Y-568300D01*
X-629783Y-569350D01*
X-629617Y-570400D01*
X-629367Y-571100D01*
X-628867Y-571800D01*
X-628283Y-572267D01*
X-627700Y-572500D01*
X-627117D01*
X-626533Y-572267D01*
X-626033Y-571917D01*
X-625617Y-571450D01*
G01X-620900Y-572500D02*
X-621567Y-572383D01*
X-622150Y-571917D01*
X-622650Y-571217D01*
X-622983Y-570400D01*
X-623150Y-569467D01*
Y-568533D01*
X-622983Y-567600D01*
X-622650Y-566783D01*
X-622150Y-566083D01*
X-621567Y-565617D01*
X-620900Y-565500D01*
X-620233Y-565617D01*
X-619650Y-566083D01*
X-619150Y-566783D01*
X-618817Y-567600D01*
X-618650Y-568533D01*
Y-569467D01*
X-618817Y-570400D01*
X-619150Y-571217D01*
X-619650Y-571917D01*
X-620233Y-572383D01*
X-620900Y-572500D01*
G01X-616017D02*
Y-565500D01*
X-612183Y-572500D01*
Y-565500D01*
G01X-609050Y-571567D02*
X-608383Y-572150D01*
X-607633Y-572500D01*
X-606967D01*
X-606300Y-572150D01*
X-605800Y-571567D01*
X-605550Y-570750D01*
X-605717Y-569933D01*
X-606133Y-569233D01*
X-606883Y-568767D01*
X-607883Y-568533D01*
X-608467Y-568067D01*
X-608717Y-567250D01*
X-608550Y-566433D01*
X-608133Y-565850D01*
X-607550Y-565500D01*
X-606967D01*
X-606383Y-565733D01*
X-605883Y-566317D01*
G01X-598833Y-572500D02*
X-602167D01*
Y-565500D01*
X-598833D01*
G01X-600167Y-568883D02*
X-602167D01*
G01X-595617Y-572500D02*
Y-565500D01*
X-591783Y-572500D01*
Y-565500D01*
G01X-586900D02*
Y-572500D01*
G01X-588817Y-565500D02*
X-584983D01*
G01X-872500Y-587500D02*
X-873167Y-587383D01*
X-873750Y-586917D01*
X-874250Y-586217D01*
X-874583Y-585400D01*
X-874750Y-584467D01*
Y-583533D01*
X-874583Y-582600D01*
X-874250Y-581783D01*
X-873750Y-581083D01*
X-873167Y-580617D01*
X-872500Y-580500D01*
X-871833Y-580617D01*
X-871250Y-581083D01*
X-870750Y-581783D01*
X-870417Y-582600D01*
X-870250Y-583533D01*
Y-584467D01*
X-870417Y-585400D01*
X-870750Y-586217D01*
X-871250Y-586917D01*
X-871833Y-587383D01*
X-872500Y-587500D01*
G01X-867283D02*
Y-580500D01*
X-864117D01*
G01X-865283Y-583883D02*
X-867283D01*
G01X-854267Y-587500D02*
Y-580500D01*
X-852100Y-586333D01*
X-849933Y-580500D01*
Y-587500D01*
G01X-846300Y-580500D02*
X-844300D01*
G01X-845300D02*
Y-587500D01*
G01X-846300D02*
X-844300D01*
G01X-836667Y-581083D02*
X-837167Y-580733D01*
X-837750Y-580500D01*
X-838417D01*
X-839167Y-580850D01*
X-839750Y-581433D01*
X-840167Y-582133D01*
X-840500Y-583300D01*
X-840583Y-584350D01*
X-840417Y-585400D01*
X-840167Y-586100D01*
X-839667Y-586800D01*
X-839083Y-587267D01*
X-838500Y-587500D01*
X-837917D01*
X-837333Y-587267D01*
X-836833Y-586917D01*
X-836417Y-586450D01*
G01X-833367Y-587500D02*
Y-580500D01*
X-831283D01*
X-830617Y-580850D01*
X-830200Y-581317D01*
X-830033Y-582250D01*
X-830200Y-583183D01*
X-830700Y-583767D01*
X-831283Y-584117D01*
X-833367D01*
G01X-831283D02*
X-830033Y-587500D01*
G01X-824900D02*
X-825567Y-587383D01*
X-826150Y-586917D01*
X-826650Y-586217D01*
X-826983Y-585400D01*
X-827150Y-584467D01*
Y-583533D01*
X-826983Y-582600D01*
X-826650Y-581783D01*
X-826150Y-581083D01*
X-825567Y-580617D01*
X-824900Y-580500D01*
X-824233Y-580617D01*
X-823650Y-581083D01*
X-823150Y-581783D01*
X-822817Y-582600D01*
X-822650Y-583533D01*
Y-584467D01*
X-822817Y-585400D01*
X-823150Y-586217D01*
X-823650Y-586917D01*
X-824233Y-587383D01*
X-824900Y-587500D01*
G01X-819850Y-586567D02*
X-819183Y-587150D01*
X-818433Y-587500D01*
X-817767D01*
X-817100Y-587150D01*
X-816600Y-586567D01*
X-816350Y-585750D01*
X-816517Y-584933D01*
X-816933Y-584233D01*
X-817683Y-583767D01*
X-818683Y-583533D01*
X-819267Y-583067D01*
X-819517Y-582250D01*
X-819350Y-581433D01*
X-818933Y-580850D01*
X-818350Y-580500D01*
X-817767D01*
X-817183Y-580733D01*
X-816683Y-581317D01*
G01X-811300Y-587500D02*
X-811967Y-587383D01*
X-812550Y-586917D01*
X-813050Y-586217D01*
X-813383Y-585400D01*
X-813550Y-584467D01*
Y-583533D01*
X-813383Y-582600D01*
X-813050Y-581783D01*
X-812550Y-581083D01*
X-811967Y-580617D01*
X-811300Y-580500D01*
X-810633Y-580617D01*
X-810050Y-581083D01*
X-809550Y-581783D01*
X-809217Y-582600D01*
X-809050Y-583533D01*
Y-584467D01*
X-809217Y-585400D01*
X-809550Y-586217D01*
X-810050Y-586917D01*
X-810633Y-587383D01*
X-811300Y-587500D01*
G01X-806083D02*
Y-580500D01*
X-802917D01*
G01X-804083Y-583883D02*
X-806083D01*
G01X-797700Y-580500D02*
Y-587500D01*
G01X-799617Y-580500D02*
X-795783D01*
G01X-782267Y-581083D02*
X-782767Y-580733D01*
X-783350Y-580500D01*
X-784017D01*
X-784767Y-580850D01*
X-785350Y-581433D01*
X-785767Y-582133D01*
X-786100Y-583300D01*
X-786183Y-584350D01*
X-786017Y-585400D01*
X-785767Y-586100D01*
X-785267Y-586800D01*
X-784683Y-587267D01*
X-784100Y-587500D01*
X-783517D01*
X-782933Y-587267D01*
X-782433Y-586917D01*
X-782017Y-586450D01*
G01X-777300Y-587500D02*
X-777967Y-587383D01*
X-778550Y-586917D01*
X-779050Y-586217D01*
X-779383Y-585400D01*
X-779550Y-584467D01*
Y-583533D01*
X-779383Y-582600D01*
X-779050Y-581783D01*
X-778550Y-581083D01*
X-777967Y-580617D01*
X-777300Y-580500D01*
X-776633Y-580617D01*
X-776050Y-581083D01*
X-775550Y-581783D01*
X-775217Y-582600D01*
X-775050Y-583533D01*
Y-584467D01*
X-775217Y-585400D01*
X-775550Y-586217D01*
X-776050Y-586917D01*
X-776633Y-587383D01*
X-777300Y-587500D01*
G01X-772167D02*
Y-580500D01*
X-770083D01*
X-769417Y-580850D01*
X-769000Y-581317D01*
X-768833Y-582250D01*
X-769000Y-583183D01*
X-769500Y-583767D01*
X-770083Y-584117D01*
X-772167D01*
G01X-770083D02*
X-768833Y-587500D01*
G01X-765367D02*
Y-580500D01*
X-763367D01*
X-762700Y-580850D01*
X-762200Y-581667D01*
X-762033Y-582600D01*
X-762200Y-583533D01*
X-762617Y-584233D01*
X-763367Y-584584D01*
X-765367D01*
G01X-756900Y-587500D02*
X-757567Y-587383D01*
X-758150Y-586917D01*
X-758650Y-586217D01*
X-758983Y-585400D01*
X-759150Y-584467D01*
Y-583533D01*
X-758983Y-582600D01*
X-758650Y-581783D01*
X-758150Y-581083D01*
X-757567Y-580617D01*
X-756900Y-580500D01*
X-756233Y-580617D01*
X-755650Y-581083D01*
X-755150Y-581783D01*
X-754817Y-582600D01*
X-754650Y-583533D01*
Y-584467D01*
X-754817Y-585400D01*
X-755150Y-586217D01*
X-755650Y-586917D01*
X-756233Y-587383D01*
X-756900Y-587500D01*
G01X-751767D02*
Y-580500D01*
X-749683D01*
X-749017Y-580850D01*
X-748600Y-581317D01*
X-748433Y-582250D01*
X-748600Y-583183D01*
X-749100Y-583767D01*
X-749683Y-584117D01*
X-751767D01*
G01X-749683D02*
X-748433Y-587500D01*
G01X-745383D02*
X-743300Y-580500D01*
X-741217Y-587500D01*
G01X-741967Y-585050D02*
X-744633D01*
G01X-736500Y-580500D02*
Y-587500D01*
G01X-738417Y-580500D02*
X-734583D01*
G01X-730700D02*
X-728700D01*
G01X-729700D02*
Y-587500D01*
G01X-730700D02*
X-728700D01*
G01X-722900D02*
X-723567Y-587383D01*
X-724150Y-586917D01*
X-724650Y-586217D01*
X-724983Y-585400D01*
X-725150Y-584467D01*
Y-583533D01*
X-724983Y-582600D01*
X-724650Y-581783D01*
X-724150Y-581083D01*
X-723567Y-580617D01*
X-722900Y-580500D01*
X-722233Y-580617D01*
X-721650Y-581083D01*
X-721150Y-581783D01*
X-720817Y-582600D01*
X-720650Y-583533D01*
Y-584467D01*
X-720817Y-585400D01*
X-721150Y-586217D01*
X-721650Y-586917D01*
X-722233Y-587383D01*
X-722900Y-587500D01*
G01X-718017D02*
Y-580500D01*
X-714183Y-587500D01*
Y-580500D01*
G01X-709300Y-587733D02*
X-709467Y-587617D01*
Y-587383D01*
X-709300Y-587267D01*
X-709133Y-587383D01*
Y-587617D01*
X-709300Y-587733D01*
G01X-870667Y-551083D02*
X-871167Y-550733D01*
X-871750Y-550500D01*
X-872417D01*
X-873167Y-550850D01*
X-873750Y-551433D01*
X-874167Y-552133D01*
X-874500Y-553300D01*
X-874583Y-554350D01*
X-874417Y-555400D01*
X-874167Y-556100D01*
X-873667Y-556800D01*
X-873083Y-557267D01*
X-872500Y-557500D01*
X-871917D01*
X-871333Y-557267D01*
X-870833Y-556917D01*
X-870417Y-556450D01*
G01X-865700Y-557500D02*
X-866367Y-557383D01*
X-866950Y-556917D01*
X-867450Y-556217D01*
X-867783Y-555400D01*
X-867950Y-554467D01*
Y-553533D01*
X-867783Y-552600D01*
X-867450Y-551783D01*
X-866950Y-551083D01*
X-866367Y-550617D01*
X-865700Y-550500D01*
X-865033Y-550617D01*
X-864450Y-551083D01*
X-863950Y-551783D01*
X-863617Y-552600D01*
X-863450Y-553533D01*
Y-554467D01*
X-863617Y-555400D01*
X-863950Y-556217D01*
X-864450Y-556917D01*
X-865033Y-557383D01*
X-865700Y-557500D01*
G01X-860817D02*
Y-550500D01*
X-856983Y-557500D01*
Y-550500D01*
G01X-853683Y-557500D02*
Y-550500D01*
X-850517D01*
G01X-851683Y-553883D02*
X-853683D01*
G01X-846300Y-550500D02*
X-844300D01*
G01X-845300D02*
Y-557500D01*
G01X-846300D02*
X-844300D01*
G01X-840333D02*
Y-550500D01*
X-838667D01*
X-838000Y-550850D01*
X-837500Y-551317D01*
X-837083Y-552017D01*
X-836750Y-552833D01*
X-836667Y-554000D01*
X-836750Y-555167D01*
X-837083Y-555983D01*
X-837500Y-556684D01*
X-838000Y-557150D01*
X-838667Y-557500D01*
X-840333D01*
G01X-830033D02*
X-833367D01*
Y-550500D01*
X-830033D01*
G01X-831367Y-553883D02*
X-833367D01*
G01X-826817Y-557500D02*
Y-550500D01*
X-822983Y-557500D01*
Y-550500D01*
G01X-816267Y-551083D02*
X-816767Y-550733D01*
X-817350Y-550500D01*
X-818017D01*
X-818767Y-550850D01*
X-819350Y-551433D01*
X-819767Y-552133D01*
X-820100Y-553300D01*
X-820183Y-554350D01*
X-820017Y-555400D01*
X-819767Y-556100D01*
X-819267Y-556800D01*
X-818683Y-557267D01*
X-818100Y-557500D01*
X-817517D01*
X-816933Y-557267D01*
X-816433Y-556917D01*
X-816017Y-556450D01*
G01X-809633Y-557500D02*
X-812967D01*
Y-550500D01*
X-809633D01*
G01X-810967Y-553883D02*
X-812967D01*
G01X-799783Y-557500D02*
X-797700Y-550500D01*
X-795617Y-557500D01*
G01X-796367Y-555050D02*
X-799033D01*
G01X-792817Y-557500D02*
Y-550500D01*
X-788983Y-557500D01*
Y-550500D01*
G01X-785933Y-557500D02*
Y-550500D01*
X-784267D01*
X-783600Y-550850D01*
X-783100Y-551317D01*
X-782683Y-552017D01*
X-782350Y-552833D01*
X-782267Y-554000D01*
X-782350Y-555167D01*
X-782683Y-555983D01*
X-783100Y-556684D01*
X-783600Y-557150D01*
X-784267Y-557500D01*
X-785933D01*
G01X-771500Y-550500D02*
X-769500D01*
G01X-770500D02*
Y-557500D01*
G01X-771500D02*
X-769500D01*
G01X-763700Y-550500D02*
Y-557500D01*
G01X-765617Y-550500D02*
X-761783D01*
G01X-758650Y-556567D02*
X-757983Y-557150D01*
X-757233Y-557500D01*
X-756567D01*
X-755900Y-557150D01*
X-755400Y-556567D01*
X-755150Y-555750D01*
X-755317Y-554933D01*
X-755733Y-554233D01*
X-756483Y-553767D01*
X-757483Y-553533D01*
X-758067Y-553067D01*
X-758317Y-552250D01*
X-758150Y-551433D01*
X-757733Y-550850D01*
X-757150Y-550500D01*
X-756567D01*
X-755983Y-550733D01*
X-755483Y-551317D01*
G01X-741467Y-551083D02*
X-741967Y-550733D01*
X-742550Y-550500D01*
X-743217D01*
X-743967Y-550850D01*
X-744550Y-551433D01*
X-744967Y-552133D01*
X-745300Y-553300D01*
X-745383Y-554350D01*
X-745217Y-555400D01*
X-744967Y-556100D01*
X-744467Y-556800D01*
X-743883Y-557267D01*
X-743300Y-557500D01*
X-742717D01*
X-742133Y-557267D01*
X-741633Y-556917D01*
X-741217Y-556450D01*
G01X-736500Y-557500D02*
X-737167Y-557383D01*
X-737750Y-556917D01*
X-738250Y-556217D01*
X-738583Y-555400D01*
X-738750Y-554467D01*
Y-553533D01*
X-738583Y-552600D01*
X-738250Y-551783D01*
X-737750Y-551083D01*
X-737167Y-550617D01*
X-736500Y-550500D01*
X-735833Y-550617D01*
X-735250Y-551083D01*
X-734750Y-551783D01*
X-734417Y-552600D01*
X-734250Y-553533D01*
Y-554467D01*
X-734417Y-555400D01*
X-734750Y-556217D01*
X-735250Y-556917D01*
X-735833Y-557383D01*
X-736500Y-557500D01*
G01X-731617D02*
Y-550500D01*
X-727783Y-557500D01*
Y-550500D01*
G01X-722900D02*
Y-557500D01*
G01X-724817Y-550500D02*
X-720983D01*
G01X-714433Y-557500D02*
X-717767D01*
Y-550500D01*
X-714433D01*
G01X-715767Y-553883D02*
X-717767D01*
G01X-711217Y-557500D02*
Y-550500D01*
X-707383Y-557500D01*
Y-550500D01*
G01X-702500D02*
Y-557500D01*
G01X-704417Y-550500D02*
X-700583D01*
G01X-697450Y-556567D02*
X-696783Y-557150D01*
X-696033Y-557500D01*
X-695367D01*
X-694700Y-557150D01*
X-694200Y-556567D01*
X-693950Y-555750D01*
X-694117Y-554933D01*
X-694533Y-554233D01*
X-695283Y-553767D01*
X-696283Y-553533D01*
X-696867Y-553067D01*
X-697117Y-552250D01*
X-696950Y-551433D01*
X-696533Y-550850D01*
X-695950Y-550500D01*
X-695367D01*
X-694783Y-550733D01*
X-694283Y-551317D01*
G01X-684267Y-557500D02*
Y-550500D01*
X-682100Y-556333D01*
X-679933Y-550500D01*
Y-557500D01*
G01X-677383D02*
X-675300Y-550500D01*
X-673217Y-557500D01*
G01X-673967Y-555050D02*
X-676633D01*
G01X-668500Y-557500D02*
Y-554350D01*
X-670167Y-550500D01*
G01X-666833D02*
X-668500Y-554350D01*
G01X-656817Y-557500D02*
Y-550500D01*
X-652983Y-557500D01*
Y-550500D01*
G01X-648100Y-557500D02*
X-648767Y-557383D01*
X-649350Y-556917D01*
X-649850Y-556217D01*
X-650183Y-555400D01*
X-650350Y-554467D01*
Y-553533D01*
X-650183Y-552600D01*
X-649850Y-551783D01*
X-649350Y-551083D01*
X-648767Y-550617D01*
X-648100Y-550500D01*
X-647433Y-550617D01*
X-646850Y-551083D01*
X-646350Y-551783D01*
X-646017Y-552600D01*
X-645850Y-553533D01*
Y-554467D01*
X-646017Y-555400D01*
X-646350Y-556217D01*
X-646850Y-556917D01*
X-647433Y-557383D01*
X-648100Y-557500D01*
G01X-641300Y-550500D02*
Y-557500D01*
G01X-643217Y-550500D02*
X-639383D01*
G01X-627033Y-553767D02*
X-626700Y-553417D01*
X-626450Y-552833D01*
X-626283Y-552017D01*
X-626450Y-551317D01*
X-626783Y-550850D01*
X-627367Y-550500D01*
X-629617D01*
Y-557500D01*
X-626867D01*
X-626283Y-557033D01*
X-625950Y-556333D01*
X-625783Y-555517D01*
X-625950Y-554700D01*
X-626450Y-554000D01*
X-627033Y-553767D01*
X-629617D01*
G01X-619233Y-557500D02*
X-622567D01*
Y-550500D01*
X-619233D01*
G01X-620567Y-553883D02*
X-622567D01*
G01X-870667Y-536083D02*
X-871167Y-535733D01*
X-871750Y-535500D01*
X-872417D01*
X-873167Y-535850D01*
X-873750Y-536433D01*
X-874167Y-537133D01*
X-874500Y-538300D01*
X-874583Y-539350D01*
X-874417Y-540400D01*
X-874167Y-541100D01*
X-873667Y-541800D01*
X-873083Y-542267D01*
X-872500Y-542500D01*
X-871917D01*
X-871333Y-542267D01*
X-870833Y-541917D01*
X-870417Y-541450D01*
G01X-865700Y-542500D02*
X-866367Y-542383D01*
X-866950Y-541917D01*
X-867450Y-541217D01*
X-867783Y-540400D01*
X-867950Y-539467D01*
Y-538533D01*
X-867783Y-537600D01*
X-867450Y-536783D01*
X-866950Y-536083D01*
X-866367Y-535617D01*
X-865700Y-535500D01*
X-865033Y-535617D01*
X-864450Y-536083D01*
X-863950Y-536783D01*
X-863617Y-537600D01*
X-863450Y-538533D01*
Y-539467D01*
X-863617Y-540400D01*
X-863950Y-541217D01*
X-864450Y-541917D01*
X-865033Y-542383D01*
X-865700Y-542500D01*
G01X-860567D02*
Y-535500D01*
X-858483D01*
X-857817Y-535850D01*
X-857400Y-536317D01*
X-857233Y-537250D01*
X-857400Y-538183D01*
X-857900Y-538767D01*
X-858483Y-539117D01*
X-860567D01*
G01X-858483D02*
X-857233Y-542500D01*
G01X-853767D02*
Y-535500D01*
X-851767D01*
X-851100Y-535850D01*
X-850600Y-536667D01*
X-850433Y-537600D01*
X-850600Y-538533D01*
X-851017Y-539233D01*
X-851767Y-539584D01*
X-853767D01*
G01X-845300Y-542500D02*
X-845967Y-542383D01*
X-846550Y-541917D01*
X-847050Y-541217D01*
X-847383Y-540400D01*
X-847550Y-539467D01*
Y-538533D01*
X-847383Y-537600D01*
X-847050Y-536783D01*
X-846550Y-536083D01*
X-845967Y-535617D01*
X-845300Y-535500D01*
X-844633Y-535617D01*
X-844050Y-536083D01*
X-843550Y-536783D01*
X-843217Y-537600D01*
X-843050Y-538533D01*
Y-539467D01*
X-843217Y-540400D01*
X-843550Y-541217D01*
X-844050Y-541917D01*
X-844633Y-542383D01*
X-845300Y-542500D01*
G01X-840167D02*
Y-535500D01*
X-838083D01*
X-837417Y-535850D01*
X-837000Y-536317D01*
X-836833Y-537250D01*
X-837000Y-538183D01*
X-837500Y-538767D01*
X-838083Y-539117D01*
X-840167D01*
G01X-838083D02*
X-836833Y-542500D01*
G01X-833783D02*
X-831700Y-535500D01*
X-829617Y-542500D01*
G01X-830367Y-540050D02*
X-833033D01*
G01X-824900Y-535500D02*
Y-542500D01*
G01X-826817Y-535500D02*
X-822983D01*
G01X-819100D02*
X-817100D01*
G01X-818100D02*
Y-542500D01*
G01X-819100D02*
X-817100D01*
G01X-811300D02*
X-811967Y-542383D01*
X-812550Y-541917D01*
X-813050Y-541217D01*
X-813383Y-540400D01*
X-813550Y-539467D01*
Y-538533D01*
X-813383Y-537600D01*
X-813050Y-536783D01*
X-812550Y-536083D01*
X-811967Y-535617D01*
X-811300Y-535500D01*
X-810633Y-535617D01*
X-810050Y-536083D01*
X-809550Y-536783D01*
X-809217Y-537600D01*
X-809050Y-538533D01*
Y-539467D01*
X-809217Y-540400D01*
X-809550Y-541217D01*
X-810050Y-541917D01*
X-810633Y-542383D01*
X-811300Y-542500D01*
G01X-806417D02*
Y-535500D01*
X-802583Y-542500D01*
Y-535500D01*
G01X-797700Y-542733D02*
X-797867Y-542617D01*
Y-542383D01*
X-797700Y-542267D01*
X-797533Y-542383D01*
Y-542617D01*
X-797700Y-542733D01*
G01X-784100Y-535500D02*
Y-542500D01*
G01X-786017Y-535500D02*
X-782183D01*
G01X-779050Y-542500D02*
Y-535500D01*
G01X-775550D02*
Y-542500D01*
G01Y-539000D02*
X-779050D01*
G01X-771500Y-535500D02*
X-769500D01*
G01X-770500D02*
Y-542500D01*
G01X-771500D02*
X-769500D01*
G01X-765450Y-541567D02*
X-764783Y-542150D01*
X-764033Y-542500D01*
X-763367D01*
X-762700Y-542150D01*
X-762200Y-541567D01*
X-761950Y-540750D01*
X-762117Y-539933D01*
X-762533Y-539233D01*
X-763283Y-538767D01*
X-764283Y-538533D01*
X-764867Y-538067D01*
X-765117Y-537250D01*
X-764950Y-536433D01*
X-764533Y-535850D01*
X-763950Y-535500D01*
X-763367D01*
X-762783Y-535733D01*
X-762283Y-536317D01*
G01X-751933Y-542500D02*
Y-535500D01*
X-750267D01*
X-749600Y-535850D01*
X-749100Y-536317D01*
X-748683Y-537017D01*
X-748350Y-537833D01*
X-748267Y-539000D01*
X-748350Y-540167D01*
X-748683Y-540983D01*
X-749100Y-541684D01*
X-749600Y-542150D01*
X-750267Y-542500D01*
X-751933D01*
G01X-744967D02*
Y-535500D01*
X-742883D01*
X-742217Y-535850D01*
X-741800Y-536317D01*
X-741633Y-537250D01*
X-741800Y-538183D01*
X-742300Y-538767D01*
X-742883Y-539117D01*
X-744967D01*
G01X-742883D02*
X-741633Y-542500D01*
G01X-738583D02*
X-736500Y-535500D01*
X-734417Y-542500D01*
G01X-735167Y-540050D02*
X-737833D01*
G01X-732200Y-535500D02*
X-731033Y-542500D01*
X-729700Y-535500D01*
X-728367Y-542500D01*
X-727200Y-535500D01*
G01X-723900D02*
X-721900D01*
G01X-722900D02*
Y-542500D01*
G01X-723900D02*
X-721900D01*
G01X-718017D02*
Y-535500D01*
X-714183Y-542500D01*
Y-535500D01*
G01X-708800Y-539000D02*
X-707133D01*
Y-541100D01*
X-707633Y-541800D01*
X-708217Y-542267D01*
X-709050Y-542500D01*
X-709883Y-542267D01*
X-710467Y-541800D01*
X-710967Y-541100D01*
X-711300Y-540283D01*
X-711467Y-539350D01*
Y-538533D01*
X-711300Y-537833D01*
X-710967Y-537017D01*
X-710467Y-536317D01*
X-709967Y-535850D01*
X-709300Y-535500D01*
X-708717D01*
X-708050Y-535733D01*
X-707550Y-536200D01*
G01X-696700Y-535500D02*
X-694700D01*
G01X-695700D02*
Y-542500D01*
G01X-696700D02*
X-694700D01*
G01X-690650Y-541567D02*
X-689983Y-542150D01*
X-689233Y-542500D01*
X-688567D01*
X-687900Y-542150D01*
X-687400Y-541567D01*
X-687150Y-540750D01*
X-687317Y-539933D01*
X-687733Y-539233D01*
X-688483Y-538767D01*
X-689483Y-538533D01*
X-690067Y-538067D01*
X-690317Y-537250D01*
X-690150Y-536433D01*
X-689733Y-535850D01*
X-689150Y-535500D01*
X-688567D01*
X-687983Y-535733D01*
X-687483Y-536317D01*
G01X-676967Y-542500D02*
Y-535500D01*
X-674883D01*
X-674217Y-535850D01*
X-673800Y-536317D01*
X-673633Y-537250D01*
X-673800Y-538183D01*
X-674300Y-538767D01*
X-674883Y-539117D01*
X-676967D01*
G01X-674883D02*
X-673633Y-542500D01*
G01X-666833D02*
X-670167D01*
Y-535500D01*
X-666833D01*
G01X-668167Y-538883D02*
X-670167D01*
G01X-659867Y-536083D02*
X-660367Y-535733D01*
X-660950Y-535500D01*
X-661617D01*
X-662367Y-535850D01*
X-662950Y-536433D01*
X-663367Y-537133D01*
X-663700Y-538300D01*
X-663783Y-539350D01*
X-663617Y-540400D01*
X-663367Y-541100D01*
X-662867Y-541800D01*
X-662283Y-542267D01*
X-661700Y-542500D01*
X-661117D01*
X-660533Y-542267D01*
X-660033Y-541917D01*
X-659617Y-541450D01*
G01X-653233Y-542500D02*
X-656567D01*
Y-535500D01*
X-653233D01*
G01X-654567Y-538883D02*
X-656567D01*
G01X-649100Y-535500D02*
X-647100D01*
G01X-648100D02*
Y-542500D01*
G01X-649100D02*
X-647100D01*
G01X-643383Y-535500D02*
X-641300Y-542500D01*
X-639217Y-535500D01*
G01X-632833Y-542500D02*
X-636167D01*
Y-535500D01*
X-632833D01*
G01X-634167Y-538883D02*
X-636167D01*
G01X-629533Y-542500D02*
Y-535500D01*
X-627867D01*
X-627200Y-535850D01*
X-626700Y-536317D01*
X-626283Y-537017D01*
X-625950Y-537833D01*
X-625867Y-539000D01*
X-625950Y-540167D01*
X-626283Y-540983D01*
X-626700Y-541684D01*
X-627200Y-542150D01*
X-627867Y-542500D01*
X-629533D01*
G01X-615100Y-535500D02*
X-613100D01*
G01X-614100D02*
Y-542500D01*
G01X-615100D02*
X-613100D01*
G01X-609217D02*
Y-535500D01*
X-605383Y-542500D01*
Y-535500D01*
G01X-872500Y-520500D02*
Y-527500D01*
G01X-874417Y-520500D02*
X-870583D01*
G01X-867450Y-527500D02*
Y-520500D01*
G01X-863950D02*
Y-527500D01*
G01Y-524000D02*
X-867450D01*
G01X-857233Y-527500D02*
X-860567D01*
Y-520500D01*
X-857233D01*
G01X-858567Y-523883D02*
X-860567D01*
G01X-846967Y-527500D02*
Y-520500D01*
X-844967D01*
X-844300Y-520850D01*
X-843800Y-521667D01*
X-843633Y-522600D01*
X-843800Y-523533D01*
X-844217Y-524233D01*
X-844967Y-524584D01*
X-846967D01*
G01X-840167Y-527500D02*
Y-520500D01*
X-838083D01*
X-837417Y-520850D01*
X-837000Y-521317D01*
X-836833Y-522250D01*
X-837000Y-523183D01*
X-837500Y-523767D01*
X-838083Y-524117D01*
X-840167D01*
G01X-838083D02*
X-836833Y-527500D01*
G01X-831700D02*
X-832367Y-527383D01*
X-832950Y-526917D01*
X-833450Y-526217D01*
X-833783Y-525400D01*
X-833950Y-524467D01*
Y-523533D01*
X-833783Y-522600D01*
X-833450Y-521783D01*
X-832950Y-521083D01*
X-832367Y-520617D01*
X-831700Y-520500D01*
X-831033Y-520617D01*
X-830450Y-521083D01*
X-829950Y-521783D01*
X-829617Y-522600D01*
X-829450Y-523533D01*
Y-524467D01*
X-829617Y-525400D01*
X-829950Y-526217D01*
X-830450Y-526917D01*
X-831033Y-527383D01*
X-831700Y-527500D01*
G01X-826567D02*
Y-520500D01*
X-824567D01*
X-823900Y-520850D01*
X-823400Y-521667D01*
X-823233Y-522600D01*
X-823400Y-523533D01*
X-823817Y-524233D01*
X-824567Y-524584D01*
X-826567D01*
G01X-819767Y-527500D02*
Y-520500D01*
X-817683D01*
X-817017Y-520850D01*
X-816600Y-521317D01*
X-816433Y-522250D01*
X-816600Y-523183D01*
X-817100Y-523767D01*
X-817683Y-524117D01*
X-819767D01*
G01X-817683D02*
X-816433Y-527500D01*
G01X-812300Y-520500D02*
X-810300D01*
G01X-811300D02*
Y-527500D01*
G01X-812300D02*
X-810300D01*
G01X-802833D02*
X-806167D01*
Y-520500D01*
X-802833D01*
G01X-804167Y-523883D02*
X-806167D01*
G01X-797700Y-520500D02*
Y-527500D01*
G01X-799617Y-520500D02*
X-795783D01*
G01X-792983Y-527500D02*
X-790900Y-520500D01*
X-788817Y-527500D01*
G01X-789567Y-525050D02*
X-792233D01*
G01X-785767Y-527500D02*
Y-520500D01*
X-783683D01*
X-783017Y-520850D01*
X-782600Y-521317D01*
X-782433Y-522250D01*
X-782600Y-523183D01*
X-783100Y-523767D01*
X-783683Y-524117D01*
X-785767D01*
G01X-783683D02*
X-782433Y-527500D01*
G01X-777300D02*
Y-524350D01*
X-778967Y-520500D01*
G01X-775633D02*
X-777300Y-524350D01*
G01X-765367Y-527500D02*
Y-520500D01*
X-763367D01*
X-762700Y-520850D01*
X-762200Y-521667D01*
X-762033Y-522600D01*
X-762200Y-523533D01*
X-762617Y-524233D01*
X-763367Y-524584D01*
X-765367D01*
G01X-758567Y-527500D02*
Y-520500D01*
X-756483D01*
X-755817Y-520850D01*
X-755400Y-521317D01*
X-755233Y-522250D01*
X-755400Y-523183D01*
X-755900Y-523767D01*
X-756483Y-524117D01*
X-758567D01*
G01X-756483D02*
X-755233Y-527500D01*
G01X-750100D02*
X-750767Y-527383D01*
X-751350Y-526917D01*
X-751850Y-526217D01*
X-752183Y-525400D01*
X-752350Y-524467D01*
Y-523533D01*
X-752183Y-522600D01*
X-751850Y-521783D01*
X-751350Y-521083D01*
X-750767Y-520617D01*
X-750100Y-520500D01*
X-749433Y-520617D01*
X-748850Y-521083D01*
X-748350Y-521783D01*
X-748017Y-522600D01*
X-747850Y-523533D01*
Y-524467D01*
X-748017Y-525400D01*
X-748350Y-526217D01*
X-748850Y-526917D01*
X-749433Y-527383D01*
X-750100Y-527500D01*
G01X-744967D02*
Y-520500D01*
X-742967D01*
X-742300Y-520850D01*
X-741800Y-521667D01*
X-741633Y-522600D01*
X-741800Y-523533D01*
X-742217Y-524233D01*
X-742967Y-524584D01*
X-744967D01*
G01X-734833Y-527500D02*
X-738167D01*
Y-520500D01*
X-734833D01*
G01X-736167Y-523883D02*
X-738167D01*
G01X-731367Y-527500D02*
Y-520500D01*
X-729283D01*
X-728617Y-520850D01*
X-728200Y-521317D01*
X-728033Y-522250D01*
X-728200Y-523183D01*
X-728700Y-523767D01*
X-729283Y-524117D01*
X-731367D01*
G01X-729283D02*
X-728033Y-527500D01*
G01X-722900Y-520500D02*
Y-527500D01*
G01X-724817Y-520500D02*
X-720983D01*
G01X-716100Y-527500D02*
Y-524350D01*
X-717767Y-520500D01*
G01X-714433D02*
X-716100Y-524350D01*
G01X-702500Y-527500D02*
X-703167Y-527383D01*
X-703750Y-526917D01*
X-704250Y-526217D01*
X-704583Y-525400D01*
X-704750Y-524467D01*
Y-523533D01*
X-704583Y-522600D01*
X-704250Y-521783D01*
X-703750Y-521083D01*
X-703167Y-520617D01*
X-702500Y-520500D01*
X-701833Y-520617D01*
X-701250Y-521083D01*
X-700750Y-521783D01*
X-700417Y-522600D01*
X-700250Y-523533D01*
Y-524467D01*
X-700417Y-525400D01*
X-700750Y-526217D01*
X-701250Y-526917D01*
X-701833Y-527383D01*
X-702500Y-527500D01*
G01X-697283D02*
Y-520500D01*
X-694117D01*
G01X-695283Y-523883D02*
X-697283D01*
G01X-684267Y-527500D02*
Y-520500D01*
X-682100Y-526333D01*
X-679933Y-520500D01*
Y-527500D01*
G01X-676300Y-520500D02*
X-674300D01*
G01X-675300D02*
Y-527500D01*
G01X-676300D02*
X-674300D01*
G01X-666667Y-521083D02*
X-667167Y-520733D01*
X-667750Y-520500D01*
X-668417D01*
X-669167Y-520850D01*
X-669750Y-521433D01*
X-670167Y-522133D01*
X-670500Y-523300D01*
X-670583Y-524350D01*
X-670417Y-525400D01*
X-670167Y-526100D01*
X-669667Y-526800D01*
X-669083Y-527267D01*
X-668500Y-527500D01*
X-667917D01*
X-667333Y-527267D01*
X-666833Y-526917D01*
X-666417Y-526450D01*
G01X-663367Y-527500D02*
Y-520500D01*
X-661283D01*
X-660617Y-520850D01*
X-660200Y-521317D01*
X-660033Y-522250D01*
X-660200Y-523183D01*
X-660700Y-523767D01*
X-661283Y-524117D01*
X-663367D01*
G01X-661283D02*
X-660033Y-527500D01*
G01X-654900D02*
X-655567Y-527383D01*
X-656150Y-526917D01*
X-656650Y-526217D01*
X-656983Y-525400D01*
X-657150Y-524467D01*
Y-523533D01*
X-656983Y-522600D01*
X-656650Y-521783D01*
X-656150Y-521083D01*
X-655567Y-520617D01*
X-654900Y-520500D01*
X-654233Y-520617D01*
X-653650Y-521083D01*
X-653150Y-521783D01*
X-652817Y-522600D01*
X-652650Y-523533D01*
Y-524467D01*
X-652817Y-525400D01*
X-653150Y-526217D01*
X-653650Y-526917D01*
X-654233Y-527383D01*
X-654900Y-527500D01*
G01X-649850Y-526567D02*
X-649183Y-527150D01*
X-648433Y-527500D01*
X-647767D01*
X-647100Y-527150D01*
X-646600Y-526567D01*
X-646350Y-525750D01*
X-646517Y-524933D01*
X-646933Y-524233D01*
X-647683Y-523767D01*
X-648683Y-523533D01*
X-649267Y-523067D01*
X-649517Y-522250D01*
X-649350Y-521433D01*
X-648933Y-520850D01*
X-648350Y-520500D01*
X-647767D01*
X-647183Y-520733D01*
X-646683Y-521317D01*
G01X-641300Y-527500D02*
X-641967Y-527383D01*
X-642550Y-526917D01*
X-643050Y-526217D01*
X-643383Y-525400D01*
X-643550Y-524467D01*
Y-523533D01*
X-643383Y-522600D01*
X-643050Y-521783D01*
X-642550Y-521083D01*
X-641967Y-520617D01*
X-641300Y-520500D01*
X-640633Y-520617D01*
X-640050Y-521083D01*
X-639550Y-521783D01*
X-639217Y-522600D01*
X-639050Y-523533D01*
Y-524467D01*
X-639217Y-525400D01*
X-639550Y-526217D01*
X-640050Y-526917D01*
X-640633Y-527383D01*
X-641300Y-527500D01*
G01X-636083D02*
Y-520500D01*
X-632917D01*
G01X-634083Y-523883D02*
X-636083D01*
G01X-627700Y-520500D02*
Y-527500D01*
G01X-629617Y-520500D02*
X-625783D01*
G01X-872500Y-505500D02*
Y-512500D01*
G01X-874417Y-505500D02*
X-870583D01*
G01X-867450Y-512500D02*
Y-505500D01*
G01X-863950D02*
Y-512500D01*
G01Y-509000D02*
X-867450D01*
G01X-859900Y-505500D02*
X-857900D01*
G01X-858900D02*
Y-512500D01*
G01X-859900D02*
X-857900D01*
G01X-853850Y-511567D02*
X-853183Y-512150D01*
X-852433Y-512500D01*
X-851767D01*
X-851100Y-512150D01*
X-850600Y-511567D01*
X-850350Y-510750D01*
X-850517Y-509933D01*
X-850933Y-509233D01*
X-851683Y-508767D01*
X-852683Y-508533D01*
X-853267Y-508067D01*
X-853517Y-507250D01*
X-853350Y-506433D01*
X-852933Y-505850D01*
X-852350Y-505500D01*
X-851767D01*
X-851183Y-505733D01*
X-850683Y-506317D01*
G01X-840333Y-512500D02*
Y-505500D01*
X-838667D01*
X-838000Y-505850D01*
X-837500Y-506317D01*
X-837083Y-507017D01*
X-836750Y-507833D01*
X-836667Y-509000D01*
X-836750Y-510167D01*
X-837083Y-510983D01*
X-837500Y-511684D01*
X-838000Y-512150D01*
X-838667Y-512500D01*
X-840333D01*
G01X-833367D02*
Y-505500D01*
X-831283D01*
X-830617Y-505850D01*
X-830200Y-506317D01*
X-830033Y-507250D01*
X-830200Y-508183D01*
X-830700Y-508767D01*
X-831283Y-509117D01*
X-833367D01*
G01X-831283D02*
X-830033Y-512500D01*
G01X-826983D02*
X-824900Y-505500D01*
X-822817Y-512500D01*
G01X-823567Y-510050D02*
X-826233D01*
G01X-820600Y-505500D02*
X-819433Y-512500D01*
X-818100Y-505500D01*
X-816767Y-512500D01*
X-815600Y-505500D01*
G01X-812300D02*
X-810300D01*
G01X-811300D02*
Y-512500D01*
G01X-812300D02*
X-810300D01*
G01X-806417D02*
Y-505500D01*
X-802583Y-512500D01*
Y-505500D01*
G01X-797200Y-509000D02*
X-795533D01*
Y-511100D01*
X-796033Y-511800D01*
X-796617Y-512267D01*
X-797450Y-512500D01*
X-798283Y-512267D01*
X-798867Y-511800D01*
X-799367Y-511100D01*
X-799700Y-510283D01*
X-799867Y-509350D01*
Y-508533D01*
X-799700Y-507833D01*
X-799367Y-507017D01*
X-798867Y-506317D01*
X-798367Y-505850D01*
X-797700Y-505500D01*
X-797117D01*
X-796450Y-505733D01*
X-795950Y-506200D01*
G01X-782267Y-506083D02*
X-782767Y-505733D01*
X-783350Y-505500D01*
X-784017D01*
X-784767Y-505850D01*
X-785350Y-506433D01*
X-785767Y-507133D01*
X-786100Y-508300D01*
X-786183Y-509350D01*
X-786017Y-510400D01*
X-785767Y-511100D01*
X-785267Y-511800D01*
X-784683Y-512267D01*
X-784100Y-512500D01*
X-783517D01*
X-782933Y-512267D01*
X-782433Y-511917D01*
X-782017Y-511450D01*
G01X-777300Y-512500D02*
X-777967Y-512383D01*
X-778550Y-511917D01*
X-779050Y-511217D01*
X-779383Y-510400D01*
X-779550Y-509467D01*
Y-508533D01*
X-779383Y-507600D01*
X-779050Y-506783D01*
X-778550Y-506083D01*
X-777967Y-505617D01*
X-777300Y-505500D01*
X-776633Y-505617D01*
X-776050Y-506083D01*
X-775550Y-506783D01*
X-775217Y-507600D01*
X-775050Y-508533D01*
Y-509467D01*
X-775217Y-510400D01*
X-775550Y-511217D01*
X-776050Y-511917D01*
X-776633Y-512383D01*
X-777300Y-512500D01*
G01X-772417D02*
Y-505500D01*
X-768583Y-512500D01*
Y-505500D01*
G01X-763700D02*
Y-512500D01*
G01X-765617Y-505500D02*
X-761783D01*
G01X-758983Y-512500D02*
X-756900Y-505500D01*
X-754817Y-512500D01*
G01X-755567Y-510050D02*
X-758233D01*
G01X-751100Y-505500D02*
X-749100D01*
G01X-750100D02*
Y-512500D01*
G01X-751100D02*
X-749100D01*
G01X-745217D02*
Y-505500D01*
X-741383Y-512500D01*
Y-505500D01*
G01X-738250Y-511567D02*
X-737583Y-512150D01*
X-736833Y-512500D01*
X-736167D01*
X-735500Y-512150D01*
X-735000Y-511567D01*
X-734750Y-510750D01*
X-734917Y-509933D01*
X-735333Y-509233D01*
X-736083Y-508767D01*
X-737083Y-508533D01*
X-737667Y-508067D01*
X-737917Y-507250D01*
X-737750Y-506433D01*
X-737333Y-505850D01*
X-736750Y-505500D01*
X-736167D01*
X-735583Y-505733D01*
X-735083Y-506317D01*
G01X-723900Y-505500D02*
X-721900D01*
G01X-722900D02*
Y-512500D01*
G01X-723900D02*
X-721900D01*
G01X-718017D02*
Y-505500D01*
X-714183Y-512500D01*
Y-505500D01*
G01X-710883Y-512500D02*
Y-505500D01*
X-707717D01*
G01X-708883Y-508883D02*
X-710883D01*
G01X-702500Y-512500D02*
X-703167Y-512383D01*
X-703750Y-511917D01*
X-704250Y-511217D01*
X-704583Y-510400D01*
X-704750Y-509467D01*
Y-508533D01*
X-704583Y-507600D01*
X-704250Y-506783D01*
X-703750Y-506083D01*
X-703167Y-505617D01*
X-702500Y-505500D01*
X-701833Y-505617D01*
X-701250Y-506083D01*
X-700750Y-506783D01*
X-700417Y-507600D01*
X-700250Y-508533D01*
Y-509467D01*
X-700417Y-510400D01*
X-700750Y-511217D01*
X-701250Y-511917D01*
X-701833Y-512383D01*
X-702500Y-512500D01*
G01X-697367D02*
Y-505500D01*
X-695283D01*
X-694617Y-505850D01*
X-694200Y-506317D01*
X-694033Y-507250D01*
X-694200Y-508183D01*
X-694700Y-508767D01*
X-695283Y-509117D01*
X-697367D01*
G01X-695283D02*
X-694033Y-512500D01*
G01X-691067D02*
Y-505500D01*
X-688900Y-511333D01*
X-686733Y-505500D01*
Y-512500D01*
G01X-684183D02*
X-682100Y-505500D01*
X-680017Y-512500D01*
G01X-680767Y-510050D02*
X-683433D01*
G01X-675300Y-505500D02*
Y-512500D01*
G01X-677217Y-505500D02*
X-673383D01*
G01X-669500D02*
X-667500D01*
G01X-668500D02*
Y-512500D01*
G01X-669500D02*
X-667500D01*
G01X-661700D02*
X-662367Y-512383D01*
X-662950Y-511917D01*
X-663450Y-511217D01*
X-663783Y-510400D01*
X-663950Y-509467D01*
Y-508533D01*
X-663783Y-507600D01*
X-663450Y-506783D01*
X-662950Y-506083D01*
X-662367Y-505617D01*
X-661700Y-505500D01*
X-661033Y-505617D01*
X-660450Y-506083D01*
X-659950Y-506783D01*
X-659617Y-507600D01*
X-659450Y-508533D01*
Y-509467D01*
X-659617Y-510400D01*
X-659950Y-511217D01*
X-660450Y-511917D01*
X-661033Y-512383D01*
X-661700Y-512500D01*
G01X-656817D02*
Y-505500D01*
X-652983Y-512500D01*
Y-505500D01*
G01X-643800D02*
X-642633Y-512500D01*
X-641300Y-505500D01*
X-639967Y-512500D01*
X-638800Y-505500D01*
G01X-636250Y-512500D02*
Y-505500D01*
G01X-632750D02*
Y-512500D01*
G01Y-509000D02*
X-636250D01*
G01X-628700Y-505500D02*
X-626700D01*
G01X-627700D02*
Y-512500D01*
G01X-628700D02*
X-626700D01*
G01X-619067Y-506083D02*
X-619567Y-505733D01*
X-620150Y-505500D01*
X-620817D01*
X-621567Y-505850D01*
X-622150Y-506433D01*
X-622567Y-507133D01*
X-622900Y-508300D01*
X-622983Y-509350D01*
X-622817Y-510400D01*
X-622567Y-511100D01*
X-622067Y-511800D01*
X-621483Y-512267D01*
X-620900Y-512500D01*
X-620317D01*
X-619733Y-512267D01*
X-619233Y-511917D01*
X-618817Y-511450D01*
G01X-615850Y-512500D02*
Y-505500D01*
G01X-612350D02*
Y-512500D01*
G01Y-509000D02*
X-615850D01*
G01X-601500Y-505500D02*
X-599500D01*
G01X-600500D02*
Y-512500D01*
G01X-601500D02*
X-599500D01*
G01X-595450Y-511567D02*
X-594783Y-512150D01*
X-594033Y-512500D01*
X-593367D01*
X-592700Y-512150D01*
X-592200Y-511567D01*
X-591950Y-510750D01*
X-592117Y-509933D01*
X-592533Y-509233D01*
X-593283Y-508767D01*
X-594283Y-508533D01*
X-594867Y-508067D01*
X-595117Y-507250D01*
X-594950Y-506433D01*
X-594533Y-505850D01*
X-593950Y-505500D01*
X-593367D01*
X-592783Y-505733D01*
X-592283Y-506317D01*
G01X-858133Y-452500D02*
Y-445500D01*
X-856467D01*
X-855800Y-445850D01*
X-855300Y-446317D01*
X-854883Y-447017D01*
X-854550Y-447833D01*
X-854467Y-449000D01*
X-854550Y-450167D01*
X-854883Y-450983D01*
X-855300Y-451684D01*
X-855800Y-452150D01*
X-856467Y-452500D01*
X-858133D01*
G01X-847833D02*
X-851167D01*
Y-445500D01*
X-847833D01*
G01X-849167Y-448883D02*
X-851167D01*
G01X-844450Y-451567D02*
X-843783Y-452150D01*
X-843033Y-452500D01*
X-842367D01*
X-841700Y-452150D01*
X-841200Y-451567D01*
X-840950Y-450750D01*
X-841117Y-449933D01*
X-841533Y-449233D01*
X-842283Y-448767D01*
X-843283Y-448533D01*
X-843867Y-448067D01*
X-844117Y-447250D01*
X-843950Y-446433D01*
X-843533Y-445850D01*
X-842950Y-445500D01*
X-842367D01*
X-841783Y-445733D01*
X-841283Y-446317D01*
G01X-836900Y-445500D02*
X-834900D01*
G01X-835900D02*
Y-452500D01*
G01X-836900D02*
X-834900D01*
G01X-828600Y-449000D02*
X-826933D01*
Y-451100D01*
X-827433Y-451800D01*
X-828017Y-452267D01*
X-828850Y-452500D01*
X-829683Y-452267D01*
X-830267Y-451800D01*
X-830767Y-451100D01*
X-831100Y-450283D01*
X-831267Y-449350D01*
Y-448533D01*
X-831100Y-447833D01*
X-830767Y-447017D01*
X-830267Y-446317D01*
X-829767Y-445850D01*
X-829100Y-445500D01*
X-828517D01*
X-827850Y-445733D01*
X-827350Y-446200D01*
G01X-824217Y-452500D02*
Y-445500D01*
X-820383Y-452500D01*
Y-445500D01*
G01X-813833Y-452500D02*
X-817167D01*
Y-445500D01*
X-813833D01*
G01X-815167Y-448883D02*
X-817167D01*
G01X-810367Y-452500D02*
Y-445500D01*
X-808283D01*
X-807617Y-445850D01*
X-807200Y-446317D01*
X-807033Y-447250D01*
X-807200Y-448183D01*
X-807700Y-448767D01*
X-808283Y-449117D01*
X-810367D01*
G01X-808283D02*
X-807033Y-452500D01*
G01X-858133D02*
Y-445500D01*
X-856467D01*
X-855800Y-445850D01*
X-855300Y-446317D01*
X-854883Y-447017D01*
X-854550Y-447833D01*
X-854467Y-449000D01*
X-854550Y-450167D01*
X-854883Y-450983D01*
X-855300Y-451684D01*
X-855800Y-452150D01*
X-856467Y-452500D01*
X-858133D01*
G01X-847833D02*
X-851167D01*
Y-445500D01*
X-847833D01*
G01X-849167Y-448883D02*
X-851167D01*
G01X-844450Y-451567D02*
X-843783Y-452150D01*
X-843033Y-452500D01*
X-842367D01*
X-841700Y-452150D01*
X-841200Y-451567D01*
X-840950Y-450750D01*
X-841117Y-449933D01*
X-841533Y-449233D01*
X-842283Y-448767D01*
X-843283Y-448533D01*
X-843867Y-448067D01*
X-844117Y-447250D01*
X-843950Y-446433D01*
X-843533Y-445850D01*
X-842950Y-445500D01*
X-842367D01*
X-841783Y-445733D01*
X-841283Y-446317D01*
G01X-836900Y-445500D02*
X-834900D01*
G01X-835900D02*
Y-452500D01*
G01X-836900D02*
X-834900D01*
G01X-828600Y-449000D02*
X-826933D01*
Y-451100D01*
X-827433Y-451800D01*
X-828017Y-452267D01*
X-828850Y-452500D01*
X-829683Y-452267D01*
X-830267Y-451800D01*
X-830767Y-451100D01*
X-831100Y-450283D01*
X-831267Y-449350D01*
Y-448533D01*
X-831100Y-447833D01*
X-830767Y-447017D01*
X-830267Y-446317D01*
X-829767Y-445850D01*
X-829100Y-445500D01*
X-828517D01*
X-827850Y-445733D01*
X-827350Y-446200D01*
G01X-824217Y-452500D02*
Y-445500D01*
X-820383Y-452500D01*
Y-445500D01*
G01X-813833Y-452500D02*
X-817167D01*
Y-445500D01*
X-813833D01*
G01X-815167Y-448883D02*
X-817167D01*
G01X-810367Y-452500D02*
Y-445500D01*
X-808283D01*
X-807617Y-445850D01*
X-807200Y-446317D01*
X-807033Y-447250D01*
X-807200Y-448183D01*
X-807700Y-448767D01*
X-808283Y-449117D01*
X-810367D01*
G01X-808283D02*
X-807033Y-452500D01*
G01X-642033Y-455000D02*
Y-448000D01*
X-640367D01*
X-639700Y-448350D01*
X-639200Y-448817D01*
X-638783Y-449517D01*
X-638450Y-450333D01*
X-638367Y-451500D01*
X-638450Y-452667D01*
X-638783Y-453483D01*
X-639200Y-454184D01*
X-639700Y-454650D01*
X-640367Y-455000D01*
X-642033D01*
G01X-635483D02*
X-633400Y-448000D01*
X-631317Y-455000D01*
G01X-632067Y-452550D02*
X-634733D01*
G01X-626600Y-448000D02*
Y-455000D01*
G01X-628517Y-448000D02*
X-624683D01*
G01X-618133Y-455000D02*
X-621467D01*
Y-448000D01*
X-618133D01*
G01X-619467Y-451383D02*
X-621467D01*
G54D18*
G01X-1184000Y-502500D02*
Y-512500D01*
G01X-1186683Y-502500D02*
X-1181317D01*
G01X-1176833Y-512500D02*
Y-502500D01*
X-1173917D01*
X-1172983Y-503000D01*
X-1172400Y-503667D01*
X-1172167Y-505000D01*
X-1172400Y-506333D01*
X-1173100Y-507167D01*
X-1173917Y-507667D01*
X-1176833D01*
G01X-1173917D02*
X-1172167Y-512500D01*
G01X-1167917D02*
X-1165000Y-502500D01*
X-1162083Y-512500D01*
G01X-1163133Y-509000D02*
X-1166867D01*
G01X-1155500Y-512500D02*
Y-508000D01*
X-1157833Y-502500D01*
G01X-1153167D02*
X-1155500Y-508000D01*
G01X-1135567Y-507167D02*
X-1135100Y-506667D01*
X-1134750Y-505834D01*
X-1134517Y-504667D01*
X-1134750Y-503667D01*
X-1135217Y-503000D01*
X-1136033Y-502500D01*
X-1139183D01*
Y-512500D01*
X-1135333D01*
X-1134517Y-511833D01*
X-1134050Y-510833D01*
X-1133817Y-509667D01*
X-1134050Y-508500D01*
X-1134750Y-507500D01*
X-1135567Y-507167D01*
X-1139183D01*
G01X-1129917Y-512500D02*
X-1127000Y-502500D01*
X-1124083Y-512500D01*
G01X-1125133Y-509000D02*
X-1128867D01*
G01X-1114933Y-503333D02*
X-1115633Y-502833D01*
X-1116450Y-502500D01*
X-1117383D01*
X-1118433Y-503000D01*
X-1119250Y-503833D01*
X-1119833Y-504833D01*
X-1120300Y-506500D01*
X-1120417Y-508000D01*
X-1120183Y-509500D01*
X-1119833Y-510500D01*
X-1119133Y-511500D01*
X-1118317Y-512167D01*
X-1117500Y-512500D01*
X-1116683D01*
X-1115867Y-512167D01*
X-1115167Y-511667D01*
X-1114583Y-511000D01*
G01X-1110567Y-512500D02*
Y-502500D01*
G01X-1106133D02*
X-1110567Y-508667D01*
G01X-1105433Y-512500D02*
X-1108583Y-505834D01*
G01X-1100833Y-512500D02*
Y-502500D01*
X-1098033D01*
X-1097100Y-503000D01*
X-1096400Y-504167D01*
X-1096167Y-505500D01*
X-1096400Y-506833D01*
X-1096983Y-507833D01*
X-1098033Y-508334D01*
X-1100833D01*
G01X-1091333Y-502500D02*
Y-512500D01*
X-1086667D01*
G01X-1082417D02*
X-1079500Y-502500D01*
X-1076583Y-512500D01*
G01X-1077633Y-509000D02*
X-1081367D01*
G01X-1072683Y-512500D02*
Y-502500D01*
X-1067317Y-512500D01*
Y-502500D01*
G01X-1058167Y-512500D02*
X-1062833D01*
Y-502500D01*
X-1058167D01*
G01X-1060033Y-507333D02*
X-1062833D01*
G01X-1043717Y-512500D02*
Y-502500D01*
X-1039283D01*
G01X-1040917Y-507333D02*
X-1043717D01*
G01X-1034917Y-512500D02*
X-1032000Y-502500D01*
X-1029083Y-512500D01*
G01X-1030133Y-509000D02*
X-1033867D01*
G01X-1021567Y-507167D02*
X-1021100Y-506667D01*
X-1020750Y-505834D01*
X-1020517Y-504667D01*
X-1020750Y-503667D01*
X-1021217Y-503000D01*
X-1022033Y-502500D01*
X-1025183D01*
Y-512500D01*
X-1021333D01*
X-1020517Y-511833D01*
X-1020050Y-510833D01*
X-1019817Y-509667D01*
X-1020050Y-508500D01*
X-1020750Y-507500D01*
X-1021567Y-507167D01*
X-1025183D01*
G01X-1002567D02*
X-1002100Y-506667D01*
X-1001750Y-505834D01*
X-1001517Y-504667D01*
X-1001750Y-503667D01*
X-1002217Y-503000D01*
X-1003033Y-502500D01*
X-1006183D01*
Y-512500D01*
X-1002333D01*
X-1001517Y-511833D01*
X-1001050Y-510833D01*
X-1000817Y-509667D01*
X-1001050Y-508500D01*
X-1001750Y-507500D01*
X-1002567Y-507167D01*
X-1006183D01*
G01X-985083Y-515833D02*
X-986250Y-514167D01*
X-986833Y-512500D01*
Y-505834D01*
X-986250Y-504167D01*
X-985083Y-502500D01*
G01X-975000Y-512500D02*
X-975933Y-512333D01*
X-976750Y-511667D01*
X-977450Y-510667D01*
X-977917Y-509500D01*
X-978150Y-508167D01*
Y-506833D01*
X-977917Y-505500D01*
X-977450Y-504333D01*
X-976750Y-503333D01*
X-975933Y-502667D01*
X-975000Y-502500D01*
X-974067Y-502667D01*
X-973250Y-503333D01*
X-972550Y-504333D01*
X-972083Y-505500D01*
X-971850Y-506833D01*
Y-508167D01*
X-972083Y-509500D01*
X-972550Y-510667D01*
X-973250Y-511667D01*
X-974067Y-512333D01*
X-975000Y-512500D01*
G01X-967950Y-511167D02*
X-967017Y-512000D01*
X-965967Y-512500D01*
X-965033D01*
X-964100Y-512000D01*
X-963400Y-511167D01*
X-963050Y-510000D01*
X-963283Y-508834D01*
X-963867Y-507833D01*
X-964917Y-507167D01*
X-966317Y-506833D01*
X-967133Y-506167D01*
X-967483Y-505000D01*
X-967250Y-503833D01*
X-966667Y-503000D01*
X-965850Y-502500D01*
X-965033D01*
X-964217Y-502833D01*
X-963517Y-503667D01*
G01X-958333Y-512500D02*
Y-502500D01*
X-955533D01*
X-954600Y-503000D01*
X-953900Y-504167D01*
X-953667Y-505500D01*
X-953900Y-506833D01*
X-954483Y-507833D01*
X-955533Y-508334D01*
X-958333D01*
G01X-945917Y-515833D02*
X-944750Y-514167D01*
X-944167Y-512500D01*
Y-505834D01*
X-944750Y-504167D01*
X-945917Y-502500D01*
G01X-902000Y-470000D02*
Y-460000D01*
X-903400Y-462000D01*
G01Y-470000D02*
X-900600D01*
G01X-892500Y-470333D02*
X-892733Y-470167D01*
Y-469833D01*
X-892500Y-469667D01*
X-892267Y-469833D01*
Y-470167D01*
X-892500Y-470333D01*
G01Y-465834D02*
X-892733Y-465667D01*
Y-465333D01*
X-892500Y-465167D01*
X-892267Y-465333D01*
Y-465667D01*
X-892500Y-465834D01*
G01X-883000Y-470000D02*
Y-460000D01*
X-884400Y-462000D01*
G01Y-470000D02*
X-881600D01*
G01X-785060Y-472187D02*
X-784127Y-473020D01*
X-783077Y-473520D01*
X-782143D01*
X-781210Y-473020D01*
X-780510Y-472187D01*
X-780160Y-471020D01*
X-780393Y-469854D01*
X-780977Y-468853D01*
X-782027Y-468187D01*
X-783427Y-467853D01*
X-784243Y-467187D01*
X-784593Y-466020D01*
X-784360Y-464853D01*
X-783777Y-464020D01*
X-782960Y-463520D01*
X-782143D01*
X-781327Y-463853D01*
X-780627Y-464687D01*
G01X-775560Y-473520D02*
Y-463520D01*
G01X-770660D02*
Y-473520D01*
G01Y-468520D02*
X-775560D01*
G01X-766527Y-473520D02*
X-763610Y-463520D01*
X-760693Y-473520D01*
G01X-761743Y-470020D02*
X-765477D01*
G01X-757610Y-463520D02*
X-755977Y-473520D01*
X-754110Y-463520D01*
X-752243Y-473520D01*
X-750610Y-463520D01*
G01X-668067Y-470500D02*
X-667367Y-471667D01*
X-666433Y-472333D01*
X-665383Y-472500D01*
X-664450Y-472333D01*
X-663517Y-471500D01*
X-662933Y-470500D01*
X-662817Y-469500D01*
X-663050Y-468334D01*
X-663867Y-467500D01*
X-664683Y-467167D01*
X-665733D01*
G01X-664683D02*
X-663983Y-466667D01*
X-663400Y-465834D01*
X-663167Y-464833D01*
X-663400Y-463833D01*
X-663983Y-463000D01*
X-665033Y-462500D01*
X-666083Y-462667D01*
X-667133Y-463333D01*
G01X-656000Y-462500D02*
X-656933Y-462833D01*
X-657633Y-463667D01*
X-658100Y-464667D01*
X-658450Y-466000D01*
X-658567Y-467500D01*
X-658450Y-469000D01*
X-658100Y-470333D01*
X-657633Y-471334D01*
X-656933Y-472167D01*
X-656000Y-472500D01*
X-655067Y-472167D01*
X-654367Y-471334D01*
X-653900Y-470333D01*
X-653550Y-469000D01*
X-653433Y-467500D01*
X-653550Y-466000D01*
X-653900Y-464667D01*
X-654367Y-463667D01*
X-655067Y-462833D01*
X-656000Y-462500D01*
G01X-648017Y-469167D02*
X-644983D01*
G01X-639917Y-472500D02*
X-637000Y-462500D01*
X-634083Y-472500D01*
G01X-635133Y-469000D02*
X-638867D01*
G01X-629833Y-472500D02*
Y-462500D01*
X-627033D01*
X-626100Y-463000D01*
X-625400Y-464167D01*
X-625167Y-465500D01*
X-625400Y-466833D01*
X-625983Y-467833D01*
X-627033Y-468334D01*
X-629833D01*
G01X-620333Y-472500D02*
Y-462500D01*
X-617417D01*
X-616483Y-463000D01*
X-615900Y-463667D01*
X-615667Y-465000D01*
X-615900Y-466333D01*
X-616600Y-467167D01*
X-617417Y-467667D01*
X-620333D01*
G01X-617417D02*
X-615667Y-472500D01*
G01X-610017Y-469167D02*
X-606983D01*
G01X-599000Y-472500D02*
Y-462500D01*
X-600400Y-464500D01*
G01Y-472500D02*
X-597600D01*
G01X-588100D02*
Y-462500D01*
X-592417Y-469667D01*
X-586583D01*
G54D28*
G01X-1020800Y-457700D02*
G02X-1020300Y-458200I0J-500D01*
G01Y-458400D01*
G02X-1020900Y-459000I-600J0D01*
G01X-1021300D01*
G01X-1021800Y-460500D02*
Y-457700D01*
X-1020600D01*
G01X-1018340Y-459100D02*
G03I-2660J0D01*
G01X-1020700D02*
X-1020200Y-460500D01*
G54D19*
G01X-1107700Y-73400D02*
X-1080400D01*
X-1063600Y-56600D01*
G01X-1107700Y-63100D02*
X-1092100D01*
X-1077100Y-48100D01*
Y-16500D01*
X-1065800Y-5200D01*
X-1061900D01*
G01X-1107800Y-68200D02*
X-1085500D01*
X-1070400Y-53100D01*
Y-33500D01*
X-1066100Y-29200D01*
X-1062000D01*
M02*
